FILE_TYPE = MACRO_DRAWING;
SET COLOR_WIRE YELLOW;
SET COLOR_PROP ORANGE;
SET COLOR_DOT WHITE;
SET COLOR_ARC YELLOW;
SET COLOR_BODY GREEN;
SET COLOR_NOTE PURPLE;
SET PROP_DISPLAY VALUE;
SET PAGE_NUMBER P154;
FORCEADD CYUSB330468LTXI..2
(-4700 3600);
FORCEPROP 1 LAST LOCATION U6001
J 0
(-5270 5831);
DISPLAY 0.723404 (-5270 5831);
PAINT GREEN (-5270 5831);
FORCEPROP 0 LAST $SEC 2
J 0
(-5250 5975);
DISPLAY 0.680851 (-5250 5975);
PAINT MONO (-5250 5975);
DISPLAY INVISIBLE (-5250 5975);
FORCEPROP 0 LAST CDS_SEC 2
J 0
(-5250 5975);
DISPLAY 0.680851 (-5250 5975);
DISPLAY INVISIBLE (-5250 5975);
FORCEPROP 0 LASTPIN (-3975 3950) $PN 10
J 0
(-3965 3960);
DISPLAY 0.680851 (-3965 3960);
PAINT MONO (-3965 3960);
FORCEPROP 0 LASTPIN (-3975 3850) $PN 16
J 0
(-3965 3860);
DISPLAY 0.680851 (-3965 3860);
PAINT MONO (-3965 3860);
FORCEPROP 0 LASTPIN (-3975 3750) $PN 34
J 0
(-3965 3760);
DISPLAY 0.680851 (-3965 3760);
PAINT MONO (-3965 3760);
FORCEPROP 0 LASTPIN (-3975 3650) $PN 46
J 0
(-3965 3660);
DISPLAY 0.680851 (-3965 3660);
PAINT MONO (-3965 3660);
FORCEPROP 0 LASTPIN (-3975 3550) $PN 52
J 0
(-3965 3560);
DISPLAY 0.680851 (-3965 3560);
PAINT MONO (-3965 3560);
FORCEPROP 0 LASTPIN (-3975 2500) $PN 53
J 0
(-3965 2510);
DISPLAY 0.680851 (-3965 2510);
PAINT MONO (-3965 2510);
FORCEPROP 0 LASTPIN (-5425 3400) $PN 4
J 2
(-5435 3410);
DISPLAY 0.680851 (-5435 3410);
PAINT MONO (-5435 3410);
FORCEPROP 0 LASTPIN (-5425 2600) $PN 56
J 2
(-5435 2610);
DISPLAY 0.680851 (-5435 2610);
PAINT MONO (-5435 2610);
FORCEPROP 0 LASTPIN (-5425 2500) $PN 61
J 2
(-5435 2510);
DISPLAY 0.680851 (-5435 2510);
PAINT MONO (-5435 2510);
FORCEPROP 0 LASTPIN (-5425 2400) $PN 66
J 2
(-5435 2410);
DISPLAY 0.680851 (-5435 2410);
PAINT MONO (-5435 2410);
FORCEPROP 0 LASTPIN (-5425 5450) $PN 1
J 2
(-5435 5460);
DISPLAY 0.680851 (-5435 5460);
PAINT MONO (-5435 5460);
FORCEPROP 0 LASTPIN (-5425 5350) $PN 3
J 2
(-5435 5360);
DISPLAY 0.680851 (-5435 5360);
PAINT MONO (-5435 5360);
FORCEPROP 0 LASTPIN (-5425 5150) $PN 27
J 2
(-5435 5160);
DISPLAY 0.680851 (-5435 5160);
PAINT MONO (-5435 5160);
FORCEPROP 0 LASTPIN (-3975 5450) $PN 49
J 0
(-3965 5460);
DISPLAY 0.680851 (-3965 5460);
PAINT MONO (-3965 5460);
FORCEPROP 0 LASTPIN (-3975 5350) $PN 7
J 0
(-3965 5360);
DISPLAY 0.680851 (-3965 5360);
PAINT MONO (-3965 5360);
FORCEPROP 0 LASTPIN (-3975 5250) $PN 13
J 0
(-3965 5260);
DISPLAY 0.680851 (-3965 5260);
PAINT MONO (-3965 5260);
FORCEPROP 0 LASTPIN (-3975 5150) $PN 37
J 0
(-3965 5160);
DISPLAY 0.680851 (-3965 5160);
PAINT MONO (-3965 5160);
FORCEPROP 0 LASTPIN (-3975 5050) $PN 43
J 0
(-3965 5060);
DISPLAY 0.680851 (-3965 5060);
PAINT MONO (-3965 5060);
FORCEPROP 0 LASTPIN (-5425 5250) $PN 19
J 2
(-5435 5260);
DISPLAY 0.680851 (-5435 5260);
PAINT MONO (-5435 5260);
FORCEPROP 0 LASTPIN (-5425 4100) $PN 28
J 2
(-5435 4110);
DISPLAY 0.680851 (-5435 4110);
PAINT MONO (-5435 4110);
FORCEPROP 2 LAST VALUE CYUSB3304-68LTXI
J 0
(-5250 5875);
DISPLAY 0.680851 (-5250 5875);
FORCEPROP 1 LAST MATERIAL IC
J 0
(-5270 5557);
DISPLAY 0.723404 (-5270 5557);
PAINT GREEN (-5270 5557);
FORCEPROP 2 LAST PART_TYPE SMLF
J 0
(-5250 5925);
DISPLAY 0.680851 (-5250 5925);
FORCEPROP 2 LAST ROOM USB3_HUB1_CYP
J 0
(-5250 5975);
DISPLAY 0.680851 (-5250 5975);
PAINT RED (-5250 5975);
FORCEPROP 1 LAST NEEDS_NO_SIZE TRUE
J 0
(-4700 3600);
DISPLAY 0.723404 (-4700 3600);
PAINT GREEN (-4700 3600);
DISPLAY INVISIBLE (-4700 3600);
FORCEPROP 1 LAST CDS_LMAN_SYM_OUTLINE -575,1950,575,-1950
J 0
(-4700 3600);
DISPLAY 0.468085 (-4700 3600);
PAINT GREEN (-4700 3600);
DISPLAY INVISIBLE (-4700 3600);
FORCEPROP 2 LAST CDS_LIB pure_quanta
J 0
(-4700 3600);
DISPLAY INVISIBLE (-4700 3600);
FORCEPROP 1 LAST PATH I1
J 0
(-4700 3600);
DISPLAY 0.723404 (-4700 3600);
PAINT GREEN (-4700 3600);
DISPLAY INVISIBLE (-4700 3600);
FORCEPROP 1 LAST PART_NUMBER AJ033040001
J 0
(-5270 5684);
DISPLAY 0.723404 (-5270 5684);
PAINT GREEN (-5270 5684);
DISPLAY INVISIBLE (-5270 5684);
FORCEADD Q_CAP..1
(-6975 3200);
FORCEPROP 1 LAST LOCATION C6043
J 0
(-6925 3300);
DISPLAY 0.978723 (-6925 3300);
FORCEPROP 0 LAST $SEC 1
J 0
(-6925 3350);
DISPLAY 0.680851 (-6925 3350);
PAINT MONO (-6925 3350);
DISPLAY INVISIBLE (-6925 3350);
FORCEPROP 0 LAST CDS_SEC 1
J 0
(-6925 3350);
DISPLAY 0.680851 (-6925 3350);
DISPLAY INVISIBLE (-6925 3350);
FORCEPROP 1 LASTPIN (-6975 3300) $PN 1
J 0
(-6965 3280);
DISPLAY 0.787234 (-6965 3280);
PAINT MONO (-6965 3280);
FORCEPROP 1 LASTPIN (-6975 3100) $PN 2
J 0
(-6965 3080);
DISPLAY 0.787234 (-6965 3080);
PAINT MONO (-6965 3080);
FORCEPROP 2 LAST ROOM USB3_HUB1_CYP
J 0
(-6925 3350);
DISPLAY 0.553191 (-6925 3350);
PAINT RED (-6925 3350);
FORCEPROP 1 LAST VALUE 1UF
J 0
(-6925 3250);
DISPLAY 0.978723 (-6925 3250);
FORCEPROP 1 LAST PACK_TYPE C0402
J 0
(-6925 3000);
DISPLAY 0.978723 (-6925 3000);
FORCEPROP 1 LAST MATERIAL X6S
J 0
(-6925 3100);
DISPLAY 0.978723 (-6925 3100);
FORCEPROP 1 LAST VOLTAGE 25V
J 0
(-6925 3200);
DISPLAY 0.978723 (-6925 3200);
FORCEPROP 1 LAST TOLERANCE 10%
J 0
(-6925 3150);
DISPLAY 0.978723 (-6925 3150);
FORCEPROP 2 LAST CDS_LIB pure_quanta
J 0
(-6975 3200);
DISPLAY INVISIBLE (-6975 3200);
FORCEPROP 1 LAST PATH I10
J 0
(-6925 3350);
DISPLAY 0.978723 (-6925 3350);
PAINT WHITE (-6925 3350);
DISPLAY INVISIBLE (-6925 3350);
FORCEPROP 1 LAST PART_NUMBER CH5104KEB02
J 0
(-6925 3050);
DISPLAY 0.787234 (-6925 3050);
DISPLAY INVISIBLE (-6925 3050);
FORCEADD GND..1
(-6975 2825);
FORCEPROP 3 LASTPIN (-6975 2875) SIG_NAME GND\g
J 0
(-6965 2885);
DISPLAY 0.659574 (-6965 2885);
PAINT MONO (-6965 2885);
DISPLAY INVISIBLE (-6965 2885);
FORCEPROP 1 LAST SIZE 1B
J 0
(-6900 2775);
DISPLAY 0.872340 (-6900 2775);
PAINT GREEN (-6900 2775);
DISPLAY INVISIBLE (-6900 2775);
FORCEPROP 2 LAST CDS_LIB pure_quanta_power
J 0
(-6975 2825);
DISPLAY INVISIBLE (-6975 2825);
FORCEPROP 1 LAST HDL_POWER GND
J 0
(-6975 2975);
DISPLAY 0.872340 (-6975 2975);
PAINT GREEN (-6975 2975);
DISPLAY INVISIBLE (-6975 2975);
FORCEPROP 1 LAST PATH I11
J 0
(-6900 2825);
DISPLAY 0.872340 (-6900 2825);
PAINT AQUA (-6900 2825);
DISPLAY INVISIBLE (-6900 2825);
FORCEADD Q_CAP..1
(-6450 3225);
FORCEPROP 1 LAST LOCATION C6044
J 0
(-6400 3300);
DISPLAY 0.978723 (-6400 3300);
FORCEPROP 0 LAST $SEC 1
J 0
(-6400 3375);
DISPLAY 0.680851 (-6400 3375);
PAINT MONO (-6400 3375);
DISPLAY INVISIBLE (-6400 3375);
FORCEPROP 0 LAST CDS_SEC 1
J 0
(-6400 3375);
DISPLAY 0.680851 (-6400 3375);
DISPLAY INVISIBLE (-6400 3375);
FORCEPROP 1 LASTPIN (-6450 3325) $PN 1
J 0
(-6440 3305);
DISPLAY 0.787234 (-6440 3305);
PAINT MONO (-6440 3305);
FORCEPROP 1 LASTPIN (-6450 3125) $PN 2
J 0
(-6440 3105);
DISPLAY 0.787234 (-6440 3105);
PAINT MONO (-6440 3105);
FORCEPROP 1 LAST VOLTAGE 25V
J 0
(-6400 3200);
DISPLAY 0.978723 (-6400 3200);
FORCEPROP 1 LAST TOLERANCE 10%
J 0
(-6400 3150);
DISPLAY 0.978723 (-6400 3150);
FORCEPROP 1 LAST VALUE 0.1UF
J 0
(-6400 3250);
DISPLAY 0.978723 (-6400 3250);
FORCEPROP 1 LAST MATERIAL X7R
J 0
(-6400 3100);
DISPLAY 0.978723 (-6400 3100);
FORCEPROP 1 LAST PACK_TYPE 0402
J 0
(-6400 3000);
DISPLAY 0.978723 (-6400 3000);
FORCEPROP 2 LAST ROOM USB3_HUB1_CYP
J 0
(-6400 3350);
DISPLAY 0.553191 (-6400 3350);
PAINT RED (-6400 3350);
FORCEPROP 2 LAST CDS_LIB pure_quanta
J 0
(-6450 3225);
DISPLAY INVISIBLE (-6450 3225);
FORCEPROP 1 LAST PATH I12
J 0
(-6400 3375);
DISPLAY 0.978723 (-6400 3375);
PAINT WHITE (-6400 3375);
DISPLAY INVISIBLE (-6400 3375);
FORCEPROP 1 LAST PART_NUMBER CH4104K1B00
J 0
(-6400 3050);
DISPLAY 0.808511 (-6400 3050);
DISPLAY INVISIBLE (-6400 3050);
FORCEADD Q_CAP..1
(-5950 3200);
FORCEPROP 1 LAST LOCATION C6045
J 0
(-5900 3300);
DISPLAY 0.978723 (-5900 3300);
FORCEPROP 0 LAST $SEC 1
J 0
(-5900 3350);
DISPLAY 0.680851 (-5900 3350);
PAINT MONO (-5900 3350);
DISPLAY INVISIBLE (-5900 3350);
FORCEPROP 0 LAST CDS_SEC 1
J 0
(-5900 3350);
DISPLAY 0.680851 (-5900 3350);
DISPLAY INVISIBLE (-5900 3350);
FORCEPROP 1 LASTPIN (-5950 3300) $PN 1
J 0
(-5940 3280);
DISPLAY 0.787234 (-5940 3280);
PAINT MONO (-5940 3280);
FORCEPROP 1 LASTPIN (-5950 3100) $PN 2
J 0
(-5940 3080);
DISPLAY 0.787234 (-5940 3080);
PAINT MONO (-5940 3080);
FORCEPROP 2 LAST ROOM USB3_HUB1_CYP
J 0
(-5900 3350);
DISPLAY 0.553191 (-5900 3350);
PAINT RED (-5900 3350);
FORCEPROP 1 LAST PACK_TYPE C0402
J 0
(-5900 3000);
DISPLAY 0.787234 (-5900 3000);
FORCEPROP 1 LAST VALUE 0.01UF
J 0
(-5900 3250);
DISPLAY 0.787234 (-5900 3250);
FORCEPROP 1 LAST VOLTAGE 50V
J 0
(-5900 3200);
DISPLAY 0.787234 (-5900 3200);
FORCEPROP 1 LAST TOLERANCE 10%
J 0
(-5900 3150);
DISPLAY 0.787234 (-5900 3150);
FORCEPROP 1 LAST MATERIAL X7R
J 0
(-5900 3100);
DISPLAY 0.787234 (-5900 3100);
FORCEPROP 2 LAST CDS_LIB pure_quanta
J 0
(-5950 3200);
DISPLAY INVISIBLE (-5950 3200);
FORCEPROP 1 LAST PATH I13
J 0
(-5900 3350);
DISPLAY 0.978723 (-5900 3350);
PAINT WHITE (-5900 3350);
DISPLAY INVISIBLE (-5900 3350);
FORCEPROP 1 LAST PART_NUMBER CH31006KB18
J 0
(-5900 3050);
DISPLAY 0.638298 (-5900 3050);
DISPLAY INVISIBLE (-5900 3050);
FORCEADD Q_CAP..1
R 2
(-8350 2225);
FORCEPROP 1 LAST LOCATION C6046
J 2
(-8400 2325);
DISPLAY 0.978723 (-8400 2325);
FORCEPROP 0 LAST $SEC 1
J 0
(-8400 2375);
DISPLAY 0.680851 (-8400 2375);
PAINT MONO (-8400 2375);
DISPLAY INVISIBLE (-8400 2375);
FORCEPROP 0 LAST CDS_SEC 1
J 0
(-8400 2375);
DISPLAY 0.680851 (-8400 2375);
DISPLAY INVISIBLE (-8400 2375);
FORCEPROP 1 LASTPIN (-8350 2325) $PN 1
J 2
(-8360 2305);
DISPLAY 0.787234 (-8360 2305);
PAINT MONO (-8360 2305);
FORCEPROP 1 LASTPIN (-8350 2125) $PN 2
J 2
(-8360 2105);
DISPLAY 0.787234 (-8360 2105);
PAINT MONO (-8360 2105);
FORCEPROP 1 LAST MATERIAL X6S
J 2
(-8400 2125);
DISPLAY 0.978723 (-8400 2125);
FORCEPROP 1 LAST TOLERANCE 20%
J 2
(-8400 2175);
DISPLAY 0.978723 (-8400 2175);
FORCEPROP 1 LAST VOLTAGE 6.3V
J 2
(-8400 2225);
DISPLAY 0.978723 (-8400 2225);
FORCEPROP 1 LAST PACK_TYPE C0603
J 2
(-8400 2025);
DISPLAY 0.978723 (-8400 2025);
FORCEPROP 1 LAST VALUE 22UF
J 2
(-8400 2275);
DISPLAY 0.978723 (-8400 2275);
FORCEPROP 2 LAST ROOM USB3_HUB1_CYP
J 0
(-8800 2375);
DISPLAY 0.680851 (-8800 2375);
PAINT RED (-8800 2375);
FORCEPROP 2 LAST CDS_LIB pure_quanta
J 2
(-8350 2225);
DISPLAY INVISIBLE (-8350 2225);
FORCEPROP 1 LAST PATH I14
J 2
(-8400 2375);
DISPLAY 0.978723 (-8400 2375);
PAINT WHITE (-8400 2375);
DISPLAY INVISIBLE (-8400 2375);
FORCEPROP 1 LAST PART_NUMBER CH6221ME900
J 2
(-8400 2075);
DISPLAY 0.787234 (-8400 2075);
DISPLAY INVISIBLE (-8400 2075);
FORCEADD Q_CAP..1
(-8150 2225);
FORCEPROP 1 LAST LOCATION C6047
J 0
(-8100 2325);
DISPLAY 0.978723 (-8100 2325);
FORCEPROP 0 LAST $SEC 1
J 0
(-8100 2375);
DISPLAY 0.680851 (-8100 2375);
PAINT MONO (-8100 2375);
DISPLAY INVISIBLE (-8100 2375);
FORCEPROP 0 LAST CDS_SEC 1
J 0
(-8100 2375);
DISPLAY 0.680851 (-8100 2375);
DISPLAY INVISIBLE (-8100 2375);
FORCEPROP 1 LASTPIN (-8150 2325) $PN 1
J 0
(-8140 2305);
DISPLAY 0.787234 (-8140 2305);
PAINT MONO (-8140 2305);
FORCEPROP 1 LASTPIN (-8150 2125) $PN 2
J 0
(-8140 2105);
DISPLAY 0.787234 (-8140 2105);
PAINT MONO (-8140 2105);
FORCEPROP 1 LAST PACK_TYPE C0402
J 0
(-8100 2025);
DISPLAY 0.978723 (-8100 2025);
FORCEPROP 1 LAST VOLTAGE 25V
J 0
(-8100 2225);
DISPLAY 0.978723 (-8100 2225);
FORCEPROP 1 LAST TOLERANCE 10%
J 0
(-8100 2175);
DISPLAY 0.978723 (-8100 2175);
FORCEPROP 1 LAST MATERIAL X6S
J 0
(-8100 2125);
DISPLAY 0.978723 (-8100 2125);
FORCEPROP 1 LAST VALUE 1UF
J 0
(-8100 2275);
DISPLAY 0.978723 (-8100 2275);
FORCEPROP 2 LAST ROOM USB3_HUB1_CYP
J 0
(-8100 2375);
DISPLAY 0.680851 (-8100 2375);
PAINT RED (-8100 2375);
FORCEPROP 2 LAST CDS_LIB pure_quanta
J 0
(-8150 2225);
DISPLAY INVISIBLE (-8150 2225);
FORCEPROP 1 LAST PATH I15
J 0
(-8100 2375);
DISPLAY 0.978723 (-8100 2375);
PAINT WHITE (-8100 2375);
DISPLAY INVISIBLE (-8100 2375);
FORCEPROP 1 LAST PART_NUMBER CH5104KEB02
J 0
(-8100 2075);
DISPLAY 0.787234 (-8100 2075);
DISPLAY INVISIBLE (-8100 2075);
FORCEADD GND..1
(-8200 1750);
FORCEPROP 3 LASTPIN (-8200 1800) SIG_NAME GND\g
J 0
(-8190 1810);
DISPLAY 0.659574 (-8190 1810);
PAINT MONO (-8190 1810);
DISPLAY INVISIBLE (-8190 1810);
FORCEPROP 2 LAST CDS_LIB pure_quanta_power
J 0
(-8200 1750);
DISPLAY INVISIBLE (-8200 1750);
FORCEPROP 1 LAST SIZE 1B
J 0
(-8125 1700);
DISPLAY 0.872340 (-8125 1700);
PAINT GREEN (-8125 1700);
DISPLAY INVISIBLE (-8125 1700);
FORCEPROP 1 LAST HDL_POWER GND
J 0
(-8200 1900);
DISPLAY 0.872340 (-8200 1900);
PAINT GREEN (-8200 1900);
DISPLAY INVISIBLE (-8200 1900);
FORCEPROP 1 LAST PATH I16
J 0
(-8125 1750);
DISPLAY 0.872340 (-8125 1750);
PAINT AQUA (-8125 1750);
DISPLAY INVISIBLE (-8125 1750);
FORCEADD Q_CAP..1
(-7525 2125);
FORCEPROP 1 LAST LOCATION C6048
J 0
(-7475 2225);
DISPLAY 0.978723 (-7475 2225);
FORCEPROP 0 LAST $SEC 1
J 0
(-7475 2275);
DISPLAY 0.680851 (-7475 2275);
PAINT MONO (-7475 2275);
DISPLAY INVISIBLE (-7475 2275);
FORCEPROP 0 LAST CDS_SEC 1
J 0
(-7475 2275);
DISPLAY 0.680851 (-7475 2275);
DISPLAY INVISIBLE (-7475 2275);
FORCEPROP 1 LASTPIN (-7525 2225) $PN 1
J 0
(-7515 2205);
DISPLAY 0.787234 (-7515 2205);
PAINT MONO (-7515 2205);
FORCEPROP 1 LASTPIN (-7525 2025) $PN 2
J 0
(-7515 2005);
DISPLAY 0.787234 (-7515 2005);
PAINT MONO (-7515 2005);
FORCEPROP 2 LAST ROOM USB3_HUB1_CYP
J 0
(-7475 2275);
DISPLAY 0.446809 (-7475 2275);
PAINT RED (-7475 2275);
FORCEPROP 1 LAST VALUE 0.1UF
J 0
(-7475 2175);
DISPLAY 0.978723 (-7475 2175);
FORCEPROP 1 LAST MATERIAL X7R
J 0
(-7475 2025);
DISPLAY 0.978723 (-7475 2025);
FORCEPROP 1 LAST VOLTAGE 25V
J 0
(-7475 2125);
DISPLAY 0.978723 (-7475 2125);
FORCEPROP 1 LAST TOLERANCE 10%
J 0
(-7475 2075);
DISPLAY 0.978723 (-7475 2075);
FORCEPROP 1 LAST PACK_TYPE 0402
J 0
(-7475 1925);
DISPLAY 0.978723 (-7475 1925);
FORCEPROP 2 LAST CDS_LIB pure_quanta
J 0
(-7525 2125);
DISPLAY INVISIBLE (-7525 2125);
FORCEPROP 1 LAST PATH I17
J 0
(-7475 2275);
DISPLAY 0.978723 (-7475 2275);
PAINT WHITE (-7475 2275);
DISPLAY INVISIBLE (-7475 2275);
FORCEPROP 1 LAST PART_NUMBER CH4104K1B00
J 0
(-7475 1975);
DISPLAY 0.808511 (-7475 1975);
DISPLAY INVISIBLE (-7475 1975);
FORCEADD GND..1
(-7525 1775);
FORCEPROP 3 LASTPIN (-7525 1825) SIG_NAME GND\g
J 0
(-7515 1835);
DISPLAY 0.659574 (-7515 1835);
PAINT MONO (-7515 1835);
DISPLAY INVISIBLE (-7515 1835);
FORCEPROP 1 LAST SIZE 1B
J 0
(-7450 1725);
DISPLAY 0.872340 (-7450 1725);
PAINT GREEN (-7450 1725);
DISPLAY INVISIBLE (-7450 1725);
FORCEPROP 2 LAST CDS_LIB pure_quanta_power
J 0
(-7525 1775);
DISPLAY INVISIBLE (-7525 1775);
FORCEPROP 1 LAST HDL_POWER GND
J 0
(-7525 1925);
DISPLAY 0.872340 (-7525 1925);
PAINT GREEN (-7525 1925);
DISPLAY INVISIBLE (-7525 1925);
FORCEPROP 1 LAST PATH I18
J 0
(-7450 1775);
DISPLAY 0.872340 (-7450 1775);
PAINT AQUA (-7450 1775);
DISPLAY INVISIBLE (-7450 1775);
FORCEADD Q_CAP..1
(-7175 2125);
FORCEPROP 1 LAST LOCATION C6049
J 0
(-7125 2225);
DISPLAY 0.978723 (-7125 2225);
FORCEPROP 0 LAST $SEC 1
J 0
(-7125 2275);
DISPLAY 0.680851 (-7125 2275);
PAINT MONO (-7125 2275);
DISPLAY INVISIBLE (-7125 2275);
FORCEPROP 0 LAST CDS_SEC 1
J 0
(-7125 2275);
DISPLAY 0.680851 (-7125 2275);
DISPLAY INVISIBLE (-7125 2275);
FORCEPROP 1 LASTPIN (-7175 2225) $PN 1
J 0
(-7165 2205);
DISPLAY 0.787234 (-7165 2205);
PAINT MONO (-7165 2205);
FORCEPROP 1 LASTPIN (-7175 2025) $PN 2
J 0
(-7165 2005);
DISPLAY 0.787234 (-7165 2005);
PAINT MONO (-7165 2005);
FORCEPROP 1 LAST VOLTAGE 50V
J 0
(-7125 2125);
DISPLAY 0.787234 (-7125 2125);
FORCEPROP 1 LAST MATERIAL X7R
J 0
(-7125 2025);
DISPLAY 0.787234 (-7125 2025);
FORCEPROP 1 LAST TOLERANCE 10%
J 0
(-7125 2075);
DISPLAY 0.787234 (-7125 2075);
FORCEPROP 1 LAST VALUE 0.01UF
J 0
(-7125 2175);
DISPLAY 0.787234 (-7125 2175);
FORCEPROP 1 LAST PACK_TYPE C0402
J 0
(-7125 1925);
DISPLAY 0.787234 (-7125 1925);
FORCEPROP 2 LAST ROOM USB3_HUB1_CYP
J 0
(-7125 2275);
DISPLAY 0.553191 (-7125 2275);
PAINT RED (-7125 2275);
FORCEPROP 2 LAST CDS_LIB pure_quanta
J 0
(-7175 2125);
DISPLAY INVISIBLE (-7175 2125);
FORCEPROP 1 LAST PATH I19
J 0
(-7125 2275);
DISPLAY 0.978723 (-7125 2275);
PAINT WHITE (-7125 2275);
DISPLAY INVISIBLE (-7125 2275);
FORCEPROP 1 LAST PART_NUMBER CH31006KB18
J 0
(-7125 1975);
DISPLAY 0.638298 (-7125 1975);
DISPLAY INVISIBLE (-7125 1975);
FORCEADD UNIVERSAL_POWER..1
(-8400 4250);
FORCEPROP 3 LASTPIN (-8400 4200) SIG_NAME P3V3_AUX\g
J 0
(-8390 4210);
DISPLAY 0.659574 (-8390 4210);
PAINT MONO (-8390 4210);
DISPLAY INVISIBLE (-8390 4210);
FORCEPROP 1 LAST HDL_POWER P3V3_AUX
J 1
(-8400 4300);
DISPLAY 0.489362 (-8400 4300);
PAINT GREEN (-8400 4300);
FORCEPROP 2 LAST BOM_COST VR_SYSTEM
J 0
(-8400 4350);
DISPLAY 0.617021 (-8400 4350);
PAINT PURPLE (-8400 4350);
DISPLAY INVISIBLE (-8400 4350);
FORCEPROP 2 LAST CDS_LIB pure_quanta_power
J 0
(-8400 4250);
DISPLAY INVISIBLE (-8400 4250);
FORCEPROP 1 LAST PATH I2
J 0
(-8350 4275);
DISPLAY 0.872340 (-8350 4275);
PAINT AQUA (-8350 4275);
DISPLAY INVISIBLE (-8350 4275);
FORCEADD Q_CAP..1
(-6725 2125);
FORCEPROP 1 LAST LOCATION C6050
J 0
(-6675 2225);
DISPLAY 0.978723 (-6675 2225);
FORCEPROP 0 LAST $SEC 1
J 0
(-6675 2275);
DISPLAY 0.680851 (-6675 2275);
PAINT MONO (-6675 2275);
DISPLAY INVISIBLE (-6675 2275);
FORCEPROP 0 LAST CDS_SEC 1
J 0
(-6675 2275);
DISPLAY 0.680851 (-6675 2275);
DISPLAY INVISIBLE (-6675 2275);
FORCEPROP 1 LASTPIN (-6725 2225) $PN 1
J 0
(-6715 2205);
DISPLAY 0.787234 (-6715 2205);
PAINT MONO (-6715 2205);
FORCEPROP 1 LASTPIN (-6725 2025) $PN 2
J 0
(-6715 2005);
DISPLAY 0.787234 (-6715 2005);
PAINT MONO (-6715 2005);
FORCEPROP 2 LAST ROOM USB3_HUB1_CYP
J 0
(-6675 2275);
DISPLAY 0.361702 (-6675 2275);
PAINT RED (-6675 2275);
FORCEPROP 1 LAST PACK_TYPE 0402
J 0
(-6675 1925);
DISPLAY 0.978723 (-6675 1925);
FORCEPROP 1 LAST VALUE 0.1UF
J 0
(-6675 2175);
DISPLAY 0.978723 (-6675 2175);
FORCEPROP 1 LAST VOLTAGE 25V
J 0
(-6675 2125);
DISPLAY 0.978723 (-6675 2125);
FORCEPROP 1 LAST MATERIAL X7R
J 0
(-6675 2025);
DISPLAY 0.978723 (-6675 2025);
FORCEPROP 1 LAST TOLERANCE 10%
J 0
(-6675 2075);
DISPLAY 0.978723 (-6675 2075);
FORCEPROP 2 LAST CDS_LIB pure_quanta
J 0
(-6725 2125);
DISPLAY INVISIBLE (-6725 2125);
FORCEPROP 1 LAST PATH I20
J 0
(-6675 2275);
DISPLAY 0.978723 (-6675 2275);
PAINT WHITE (-6675 2275);
DISPLAY INVISIBLE (-6675 2275);
FORCEPROP 1 LAST PART_NUMBER CH4104K1B00
J 0
(-6675 1975);
DISPLAY 0.808511 (-6675 1975);
DISPLAY INVISIBLE (-6675 1975);
FORCEADD Q_CAP..1
(-6400 2125);
FORCEPROP 1 LAST LOCATION C6051
J 0
(-6350 2225);
DISPLAY 0.978723 (-6350 2225);
FORCEPROP 0 LAST $SEC 1
J 0
(-6350 2275);
DISPLAY 0.680851 (-6350 2275);
PAINT MONO (-6350 2275);
DISPLAY INVISIBLE (-6350 2275);
FORCEPROP 0 LAST CDS_SEC 1
J 0
(-6350 2275);
DISPLAY 0.680851 (-6350 2275);
DISPLAY INVISIBLE (-6350 2275);
FORCEPROP 1 LASTPIN (-6400 2225) $PN 1
J 0
(-6390 2205);
DISPLAY 0.787234 (-6390 2205);
PAINT MONO (-6390 2205);
FORCEPROP 1 LASTPIN (-6400 2025) $PN 2
J 0
(-6390 2005);
DISPLAY 0.787234 (-6390 2005);
PAINT MONO (-6390 2005);
FORCEPROP 2 LAST ROOM USB3_HUB1_CYP
J 0
(-6350 2275);
DISPLAY 0.446809 (-6350 2275);
PAINT RED (-6350 2275);
FORCEPROP 1 LAST TOLERANCE 10%
J 0
(-6350 2075);
DISPLAY 0.787234 (-6350 2075);
FORCEPROP 1 LAST MATERIAL X7R
J 0
(-6350 2025);
DISPLAY 0.787234 (-6350 2025);
FORCEPROP 1 LAST PACK_TYPE C0402
J 0
(-6350 1925);
DISPLAY 0.787234 (-6350 1925);
FORCEPROP 1 LAST VOLTAGE 50V
J 0
(-6350 2125);
DISPLAY 0.787234 (-6350 2125);
FORCEPROP 1 LAST VALUE 0.01UF
J 0
(-6350 2175);
DISPLAY 0.787234 (-6350 2175);
FORCEPROP 2 LAST CDS_LIB pure_quanta
J 0
(-6400 2125);
DISPLAY INVISIBLE (-6400 2125);
FORCEPROP 1 LAST PATH I21
J 0
(-6350 2275);
DISPLAY 0.978723 (-6350 2275);
PAINT WHITE (-6350 2275);
DISPLAY INVISIBLE (-6350 2275);
FORCEPROP 1 LAST PART_NUMBER CH31006KB18
J 0
(-6350 1975);
DISPLAY 0.638298 (-6350 1975);
DISPLAY INVISIBLE (-6350 1975);
FORCEADD Q_CAP..1
(-5725 2125);
FORCEPROP 1 LAST LOCATION C6053
J 0
(-5675 2225);
DISPLAY 0.978723 (-5675 2225);
FORCEPROP 0 LAST $SEC 1
J 0
(-5675 2275);
DISPLAY 0.680851 (-5675 2275);
PAINT MONO (-5675 2275);
DISPLAY INVISIBLE (-5675 2275);
FORCEPROP 0 LAST CDS_SEC 1
J 0
(-5675 2275);
DISPLAY 0.680851 (-5675 2275);
DISPLAY INVISIBLE (-5675 2275);
FORCEPROP 1 LASTPIN (-5725 2225) $PN 1
J 0
(-5715 2205);
DISPLAY 0.787234 (-5715 2205);
PAINT MONO (-5715 2205);
FORCEPROP 1 LASTPIN (-5725 2025) $PN 2
J 0
(-5715 2005);
DISPLAY 0.787234 (-5715 2005);
PAINT MONO (-5715 2005);
FORCEPROP 1 LAST VOLTAGE 50V
J 0
(-5675 2125);
DISPLAY 0.787234 (-5675 2125);
FORCEPROP 1 LAST PACK_TYPE C0402
J 0
(-5675 1925);
DISPLAY 0.787234 (-5675 1925);
FORCEPROP 1 LAST MATERIAL X7R
J 0
(-5675 2025);
DISPLAY 0.787234 (-5675 2025);
FORCEPROP 1 LAST TOLERANCE 10%
J 0
(-5675 2075);
DISPLAY 0.787234 (-5675 2075);
FORCEPROP 1 LAST VALUE 0.01UF
J 0
(-5675 2175);
DISPLAY 0.787234 (-5675 2175);
FORCEPROP 2 LAST ROOM USB3_HUB1_CYP
J 0
(-5675 2275);
DISPLAY 0.446809 (-5675 2275);
PAINT RED (-5675 2275);
FORCEPROP 2 LAST CDS_LIB pure_quanta
J 0
(-5725 2125);
DISPLAY INVISIBLE (-5725 2125);
FORCEPROP 1 LAST PATH I22
J 0
(-5675 2275);
DISPLAY 0.978723 (-5675 2275);
PAINT WHITE (-5675 2275);
DISPLAY INVISIBLE (-5675 2275);
FORCEPROP 1 LAST PART_NUMBER CH31006KB18
J 0
(-5675 1975);
DISPLAY 0.638298 (-5675 1975);
DISPLAY INVISIBLE (-5675 1975);
FORCEADD Q_CAP..1
(-6025 2125);
FORCEPROP 1 LAST LOCATION C6052
J 0
(-5975 2225);
DISPLAY 0.978723 (-5975 2225);
FORCEPROP 0 LAST $SEC 1
J 0
(-5975 2275);
DISPLAY 0.680851 (-5975 2275);
PAINT MONO (-5975 2275);
DISPLAY INVISIBLE (-5975 2275);
FORCEPROP 0 LAST CDS_SEC 1
J 0
(-5975 2275);
DISPLAY 0.680851 (-5975 2275);
DISPLAY INVISIBLE (-5975 2275);
FORCEPROP 1 LASTPIN (-6025 2225) $PN 1
J 0
(-6015 2205);
DISPLAY 0.787234 (-6015 2205);
PAINT MONO (-6015 2205);
FORCEPROP 1 LASTPIN (-6025 2025) $PN 2
J 0
(-6015 2005);
DISPLAY 0.787234 (-6015 2005);
PAINT MONO (-6015 2005);
FORCEPROP 2 LAST ROOM USB3_HUB1_CYP
J 0
(-5975 2275);
DISPLAY 0.361702 (-5975 2275);
PAINT RED (-5975 2275);
FORCEPROP 1 LAST VALUE 0.1UF
J 0
(-5975 2175);
DISPLAY 0.978723 (-5975 2175);
FORCEPROP 1 LAST MATERIAL X7R
J 0
(-5975 2025);
DISPLAY 0.978723 (-5975 2025);
FORCEPROP 1 LAST TOLERANCE 10%
J 0
(-5975 2075);
DISPLAY 0.978723 (-5975 2075);
FORCEPROP 1 LAST VOLTAGE 25V
J 0
(-5975 2125);
DISPLAY 0.978723 (-5975 2125);
FORCEPROP 1 LAST PACK_TYPE 0402
J 0
(-5975 1925);
DISPLAY 0.978723 (-5975 1925);
FORCEPROP 2 LAST CDS_LIB pure_quanta
J 0
(-6025 2125);
DISPLAY INVISIBLE (-6025 2125);
FORCEPROP 1 LAST PATH I23
J 0
(-5975 2275);
DISPLAY 0.978723 (-5975 2275);
PAINT WHITE (-5975 2275);
DISPLAY INVISIBLE (-5975 2275);
FORCEPROP 1 LAST PART_NUMBER CH4104K1B00
J 0
(-5975 1975);
DISPLAY 0.808511 (-5975 1975);
DISPLAY INVISIBLE (-5975 1975);
FORCEADD GND..1
(-6725 1750);
FORCEPROP 3 LASTPIN (-6725 1800) SIG_NAME GND\g
J 0
(-6715 1810);
DISPLAY 0.659574 (-6715 1810);
PAINT MONO (-6715 1810);
DISPLAY INVISIBLE (-6715 1810);
FORCEPROP 1 LAST SIZE 1B
J 0
(-6650 1700);
DISPLAY 0.872340 (-6650 1700);
PAINT GREEN (-6650 1700);
DISPLAY INVISIBLE (-6650 1700);
FORCEPROP 2 LAST CDS_LIB pure_quanta_power
J 0
(-6725 1750);
DISPLAY INVISIBLE (-6725 1750);
FORCEPROP 1 LAST HDL_POWER GND
J 0
(-6725 1900);
DISPLAY 0.872340 (-6725 1900);
PAINT GREEN (-6725 1900);
DISPLAY INVISIBLE (-6725 1900);
FORCEPROP 1 LAST PATH I24
J 0
(-6650 1750);
DISPLAY 0.872340 (-6650 1750);
PAINT AQUA (-6650 1750);
DISPLAY INVISIBLE (-6650 1750);
FORCEADD GND..1
(-6025 1775);
FORCEPROP 3 LASTPIN (-6025 1825) SIG_NAME GND\g
J 0
(-6015 1835);
DISPLAY 0.659574 (-6015 1835);
PAINT MONO (-6015 1835);
DISPLAY INVISIBLE (-6015 1835);
FORCEPROP 2 LAST CDS_LIB pure_quanta_power
J 0
(-6025 1775);
DISPLAY INVISIBLE (-6025 1775);
FORCEPROP 1 LAST SIZE 1B
J 0
(-5950 1725);
DISPLAY 0.872340 (-5950 1725);
PAINT GREEN (-5950 1725);
DISPLAY INVISIBLE (-5950 1725);
FORCEPROP 1 LAST HDL_POWER GND
J 0
(-6025 1925);
DISPLAY 0.872340 (-6025 1925);
PAINT GREEN (-6025 1925);
DISPLAY INVISIBLE (-6025 1925);
FORCEPROP 1 LAST PATH I25
J 0
(-5950 1775);
DISPLAY 0.872340 (-5950 1775);
PAINT AQUA (-5950 1775);
DISPLAY INVISIBLE (-5950 1775);
FORCEADD Q_INDUCTOR..1
(-8400 5475);
FORCEPROP 1 LAST LOCATION L6001
J 0
(-8525 5635);
DISPLAY 0.723404 (-8525 5635);
PAINT GREEN (-8525 5635);
FORCEPROP 0 LAST $SEC 1
J 0
(-8525 5775);
DISPLAY 0.680851 (-8525 5775);
PAINT MONO (-8525 5775);
DISPLAY INVISIBLE (-8525 5775);
FORCEPROP 0 LAST CDS_SEC 1
J 0
(-8525 5775);
DISPLAY 0.680851 (-8525 5775);
DISPLAY INVISIBLE (-8525 5775);
FORCEPROP 0 LASTPIN (-8500 5450) $PN 1
J 2
(-8510 5460);
DISPLAY 0.680851 (-8510 5460);
PAINT MONO (-8510 5460);
FORCEPROP 0 LASTPIN (-8300 5450) $PN 2
J 0
(-8290 5460);
DISPLAY 0.680851 (-8290 5460);
PAINT MONO (-8290 5460);
FORCEPROP 2 LAST ROOM USB3_HUB1_CYP
J 0
(-8525 5775);
DISPLAY 0.680851 (-8525 5775);
PAINT RED (-8525 5775);
FORCEPROP 2 LAST PACK_TYPE SMLF
J 0
(-8525 5675);
DISPLAY 0.680851 (-8525 5675);
FORCEPROP 1 LAST MATERIAL IND
J 0
(-8525 5530);
DISPLAY 0.723404 (-8525 5530);
PAINT GREEN (-8525 5530);
FORCEPROP 2 LAST VALUE BLM21PG221SN1D
J 0
(-8525 5725);
DISPLAY 0.680851 (-8525 5725);
FORCEPROP 1 LAST NEEDS_NO_SIZE TRUE
J 0
(-8400 5475);
DISPLAY 0.468085 (-8400 5475);
PAINT GREEN (-8400 5475);
DISPLAY INVISIBLE (-8400 5475);
FORCEPROP 2 LAST CDS_LIB pure_quanta
J 0
(-8400 5475);
DISPLAY INVISIBLE (-8400 5475);
FORCEPROP 1 LAST PATH I26
J 0
(-8325 5530);
DISPLAY 0.723404 (-8325 5530);
PAINT GREEN (-8325 5530);
DISPLAY INVISIBLE (-8325 5530);
FORCEPROP 1 LAST PART_NUMBER CX1PG221001
J 0
(-8525 5585);
DISPLAY 0.723404 (-8525 5585);
PAINT GREEN (-8525 5585);
DISPLAY INVISIBLE (-8525 5585);
FORCEADD Q_CAP..1
R 2
(-8200 5250);
FORCEPROP 1 LAST LOCATION C6030
J 2
(-8250 5350);
DISPLAY 0.978723 (-8250 5350);
FORCEPROP 0 LAST $SEC 1
J 0
(-8250 5400);
DISPLAY 0.680851 (-8250 5400);
PAINT MONO (-8250 5400);
DISPLAY INVISIBLE (-8250 5400);
FORCEPROP 0 LAST CDS_SEC 1
J 0
(-8250 5400);
DISPLAY 0.680851 (-8250 5400);
DISPLAY INVISIBLE (-8250 5400);
FORCEPROP 1 LASTPIN (-8200 5350) $PN 1
J 2
(-8210 5330);
DISPLAY 0.787234 (-8210 5330);
PAINT MONO (-8210 5330);
FORCEPROP 1 LASTPIN (-8200 5150) $PN 2
J 2
(-8210 5130);
DISPLAY 0.787234 (-8210 5130);
PAINT MONO (-8210 5130);
FORCEPROP 2 LAST ROOM USB3_HUB1_CYP
J 0
(-8650 5000);
DISPLAY 0.680851 (-8650 5000);
PAINT RED (-8650 5000);
FORCEPROP 1 LAST TOLERANCE 20%
J 2
(-8250 5200);
DISPLAY 0.978723 (-8250 5200);
FORCEPROP 1 LAST MATERIAL X6S
J 2
(-8250 5150);
DISPLAY 0.978723 (-8250 5150);
FORCEPROP 1 LAST PACK_TYPE C0603
J 2
(-8250 5050);
DISPLAY 0.978723 (-8250 5050);
FORCEPROP 1 LAST VALUE 22UF
J 2
(-8250 5300);
DISPLAY 0.978723 (-8250 5300);
FORCEPROP 1 LAST VOLTAGE 6.3V
J 2
(-8250 5250);
DISPLAY 0.978723 (-8250 5250);
FORCEPROP 2 LAST CDS_LIB pure_quanta
J 2
(-8200 5250);
DISPLAY INVISIBLE (-8200 5250);
FORCEPROP 1 LAST PATH I27
J 2
(-8250 5400);
DISPLAY 0.978723 (-8250 5400);
PAINT WHITE (-8250 5400);
DISPLAY INVISIBLE (-8250 5400);
FORCEPROP 1 LAST PART_NUMBER CH6221ME900
J 2
(-8250 5100);
DISPLAY 0.787234 (-8250 5100);
DISPLAY INVISIBLE (-8250 5100);
FORCEADD GND..1
(-7975 4875);
FORCEPROP 3 LASTPIN (-7975 4925) SIG_NAME GND\g
J 0
(-7965 4935);
DISPLAY 0.659574 (-7965 4935);
PAINT MONO (-7965 4935);
DISPLAY INVISIBLE (-7965 4935);
FORCEPROP 1 LAST SIZE 1B
J 0
(-7900 4825);
DISPLAY 0.872340 (-7900 4825);
PAINT GREEN (-7900 4825);
DISPLAY INVISIBLE (-7900 4825);
FORCEPROP 2 LAST CDS_LIB pure_quanta_power
J 0
(-7975 4875);
DISPLAY INVISIBLE (-7975 4875);
FORCEPROP 1 LAST HDL_POWER GND
J 0
(-7975 5025);
DISPLAY 0.872340 (-7975 5025);
PAINT GREEN (-7975 5025);
DISPLAY INVISIBLE (-7975 5025);
FORCEPROP 1 LAST PATH I28
J 0
(-7900 4875);
DISPLAY 0.872340 (-7900 4875);
PAINT AQUA (-7900 4875);
DISPLAY INVISIBLE (-7900 4875);
FORCEADD Q_CAP..1
(-7975 5250);
FORCEPROP 1 LAST LOCATION C6031
J 0
(-7925 5350);
DISPLAY 0.978723 (-7925 5350);
FORCEPROP 0 LAST $SEC 1
J 0
(-7925 5400);
DISPLAY 0.680851 (-7925 5400);
PAINT MONO (-7925 5400);
DISPLAY INVISIBLE (-7925 5400);
FORCEPROP 0 LAST CDS_SEC 1
J 0
(-7925 5400);
DISPLAY 0.680851 (-7925 5400);
DISPLAY INVISIBLE (-7925 5400);
FORCEPROP 1 LASTPIN (-7975 5350) $PN 1
J 0
(-7965 5330);
DISPLAY 0.787234 (-7965 5330);
PAINT MONO (-7965 5330);
FORCEPROP 1 LASTPIN (-7975 5150) $PN 2
J 0
(-7965 5130);
DISPLAY 0.787234 (-7965 5130);
PAINT MONO (-7965 5130);
FORCEPROP 2 LAST ROOM USB3_HUB1_CYP
J 0
(-7925 5000);
DISPLAY 0.680851 (-7925 5000);
PAINT RED (-7925 5000);
FORCEPROP 1 LAST PACK_TYPE C0402
J 0
(-7925 5050);
DISPLAY 0.978723 (-7925 5050);
FORCEPROP 1 LAST TOLERANCE 10%
J 0
(-7925 5200);
DISPLAY 0.978723 (-7925 5200);
FORCEPROP 1 LAST MATERIAL X6S
J 0
(-7925 5150);
DISPLAY 0.978723 (-7925 5150);
FORCEPROP 1 LAST VALUE 1UF
J 0
(-7925 5300);
DISPLAY 0.978723 (-7925 5300);
FORCEPROP 1 LAST VOLTAGE 25V
J 0
(-7925 5250);
DISPLAY 0.978723 (-7925 5250);
FORCEPROP 2 LAST CDS_LIB pure_quanta
J 0
(-7975 5250);
DISPLAY INVISIBLE (-7975 5250);
FORCEPROP 1 LAST PATH I29
J 0
(-7925 5400);
DISPLAY 0.978723 (-7925 5400);
PAINT WHITE (-7925 5400);
DISPLAY INVISIBLE (-7925 5400);
FORCEPROP 1 LAST PART_NUMBER CH5104KEB02
J 0
(-7925 5100);
DISPLAY 0.787234 (-7925 5100);
DISPLAY INVISIBLE (-7925 5100);
FORCEADD Q_INDUCTOR..1
(-8100 3425);
FORCEPROP 1 LAST LOCATION L6000
J 0
(-8225 3585);
DISPLAY 0.723404 (-8225 3585);
PAINT GREEN (-8225 3585);
FORCEPROP 0 LAST $SEC 1
J 0
(-8225 3725);
DISPLAY 0.680851 (-8225 3725);
PAINT MONO (-8225 3725);
DISPLAY INVISIBLE (-8225 3725);
FORCEPROP 0 LAST CDS_SEC 1
J 0
(-8225 3725);
DISPLAY 0.680851 (-8225 3725);
DISPLAY INVISIBLE (-8225 3725);
FORCEPROP 0 LASTPIN (-8200 3400) $PN 1
J 2
(-8210 3410);
DISPLAY 0.680851 (-8210 3410);
PAINT MONO (-8210 3410);
FORCEPROP 0 LASTPIN (-8000 3400) $PN 2
J 0
(-7990 3410);
DISPLAY 0.680851 (-7990 3410);
PAINT MONO (-7990 3410);
FORCEPROP 2 LAST PACK_TYPE SMLF
J 0
(-8225 3625);
DISPLAY 0.680851 (-8225 3625);
FORCEPROP 2 LAST VALUE BLM21PG221SN1D
J 0
(-8225 3675);
DISPLAY 0.680851 (-8225 3675);
FORCEPROP 1 LAST MATERIAL IND
J 0
(-8225 3480);
DISPLAY 0.723404 (-8225 3480);
PAINT GREEN (-8225 3480);
FORCEPROP 2 LAST ROOM USB3_HUB1_CYP
J 0
(-8225 3725);
DISPLAY 0.680851 (-8225 3725);
PAINT RED (-8225 3725);
FORCEPROP 1 LAST NEEDS_NO_SIZE TRUE
J 0
(-8100 3425);
DISPLAY 0.468085 (-8100 3425);
PAINT GREEN (-8100 3425);
DISPLAY INVISIBLE (-8100 3425);
FORCEPROP 2 LAST CDS_LIB pure_quanta
J 0
(-8100 3425);
DISPLAY INVISIBLE (-8100 3425);
FORCEPROP 1 LAST PATH I3
J 0
(-8025 3480);
DISPLAY 0.723404 (-8025 3480);
PAINT GREEN (-8025 3480);
DISPLAY INVISIBLE (-8025 3480);
FORCEPROP 1 LAST PART_NUMBER CX1PG221001
J 0
(-8225 3535);
DISPLAY 0.723404 (-8225 3535);
PAINT GREEN (-8225 3535);
DISPLAY INVISIBLE (-8225 3535);
FORCEADD UNIVERSAL_POWER..1
(-7875 5825);
FORCEPROP 3 LASTPIN (-7875 5775) SIG_NAME P1V2_CPU0_USB_DVDD12\g
J 0
(-7865 5785);
DISPLAY 0.659574 (-7865 5785);
PAINT MONO (-7865 5785);
DISPLAY INVISIBLE (-7865 5785);
FORCEPROP 1 LAST HDL_POWER P1V2_CPU0_USB_DVDD12
J 1
(-7875 5875);
DISPLAY 0.489362 (-7875 5875);
PAINT GREEN (-7875 5875);
FORCEPROP 2 LAST BOM_COST VR_SYSTEM
J 0
(-7875 5925);
DISPLAY 0.617021 (-7875 5925);
PAINT PURPLE (-7875 5925);
DISPLAY INVISIBLE (-7875 5925);
FORCEPROP 2 LAST CDS_LIB pure_quanta_power
J 0
(-7875 5825);
DISPLAY INVISIBLE (-7875 5825);
FORCEPROP 1 LAST PATH I30
J 0
(-7825 5850);
DISPLAY 0.872340 (-7825 5850);
PAINT AQUA (-7825 5850);
DISPLAY INVISIBLE (-7825 5850);
FORCEADD Q_CAP..1
(-6725 4900);
FORCEPROP 1 LAST LOCATION C6035
J 0
(-6675 5000);
DISPLAY 0.638298 (-6675 5000);
FORCEPROP 0 LAST $SEC 1
J 0
(-6675 5050);
DISPLAY 0.680851 (-6675 5050);
PAINT MONO (-6675 5050);
DISPLAY INVISIBLE (-6675 5050);
FORCEPROP 0 LAST CDS_SEC 1
J 0
(-6675 5050);
DISPLAY 0.680851 (-6675 5050);
DISPLAY INVISIBLE (-6675 5050);
FORCEPROP 1 LASTPIN (-6725 5000) $PN 1
J 0
(-6715 4980);
DISPLAY 0.787234 (-6715 4980);
PAINT MONO (-6715 4980);
FORCEPROP 1 LASTPIN (-6725 4800) $PN 2
J 0
(-6715 4780);
DISPLAY 0.787234 (-6715 4780);
PAINT MONO (-6715 4780);
FORCEPROP 1 LAST PACK_TYPE C0402
J 0
(-6675 4700);
DISPLAY 0.510638 (-6675 4700);
FORCEPROP 2 LAST ROOM USB3_HUB1_CYP
J 0
(-6700 4750);
DISPLAY 0.361702 (-6700 4750);
PAINT RED (-6700 4750);
FORCEPROP 1 LAST TOLERANCE 10%
J 0
(-6675 4850);
DISPLAY 0.510638 (-6675 4850);
FORCEPROP 1 LAST MATERIAL X7R
J 0
(-6675 4800);
DISPLAY 0.510638 (-6675 4800);
FORCEPROP 1 LAST VOLTAGE 50V
J 0
(-6675 4900);
DISPLAY 0.510638 (-6675 4900);
FORCEPROP 1 LAST VALUE 0.01UF
J 0
(-6675 4950);
DISPLAY 0.510638 (-6675 4950);
FORCEPROP 2 LAST CDS_LIB pure_quanta
J 0
(-6725 4900);
DISPLAY INVISIBLE (-6725 4900);
FORCEPROP 1 LAST PATH I31
J 0
(-6675 5050);
DISPLAY 0.978723 (-6675 5050);
PAINT WHITE (-6675 5050);
DISPLAY INVISIBLE (-6675 5050);
FORCEPROP 1 LAST PART_NUMBER CH31006KB18
J 0
(-6675 4750);
DISPLAY 0.638298 (-6675 4750);
DISPLAY INVISIBLE (-6675 4750);
FORCEADD Q_CAP..1
(-6950 4925);
FORCEPROP 1 LAST LOCATION C6034
J 0
(-6900 5025);
DISPLAY 0.638298 (-6900 5025);
FORCEPROP 0 LAST $SEC 1
J 0
(-6900 5075);
DISPLAY 0.680851 (-6900 5075);
PAINT MONO (-6900 5075);
DISPLAY INVISIBLE (-6900 5075);
FORCEPROP 0 LAST CDS_SEC 1
J 0
(-6900 5075);
DISPLAY 0.680851 (-6900 5075);
DISPLAY INVISIBLE (-6900 5075);
FORCEPROP 1 LASTPIN (-6950 5025) $PN 1
J 0
(-6940 5005);
DISPLAY 0.787234 (-6940 5005);
PAINT MONO (-6940 5005);
FORCEPROP 1 LASTPIN (-6950 4825) $PN 2
J 0
(-6940 4805);
DISPLAY 0.787234 (-6940 4805);
PAINT MONO (-6940 4805);
FORCEPROP 1 LAST PACK_TYPE 0402
J 0
(-6900 4725);
DISPLAY 0.638298 (-6900 4725);
FORCEPROP 2 LAST ROOM USB3_HUB1_CYP
J 0
(-6925 4775);
DISPLAY 0.297872 (-6925 4775);
PAINT RED (-6925 4775);
FORCEPROP 1 LAST TOLERANCE 10%
J 0
(-6900 4875);
DISPLAY 0.638298 (-6900 4875);
FORCEPROP 1 LAST VALUE 0.1UF
J 0
(-6900 4975);
DISPLAY 0.638298 (-6900 4975);
FORCEPROP 1 LAST VOLTAGE 25V
J 0
(-6900 4925);
DISPLAY 0.638298 (-6900 4925);
FORCEPROP 1 LAST MATERIAL X7R
J 0
(-6900 4825);
DISPLAY 0.638298 (-6900 4825);
FORCEPROP 2 LAST CDS_LIB pure_quanta
J 0
(-6950 4925);
DISPLAY INVISIBLE (-6950 4925);
FORCEPROP 1 LAST PATH I32
J 0
(-6900 5075);
DISPLAY 0.978723 (-6900 5075);
PAINT WHITE (-6900 5075);
DISPLAY INVISIBLE (-6900 5075);
FORCEPROP 1 LAST PART_NUMBER CH4104K1B00
J 0
(-6900 4775);
DISPLAY 0.808511 (-6900 4775);
DISPLAY INVISIBLE (-6900 4775);
FORCEADD GND..1
(-6775 4525);
FORCEPROP 3 LASTPIN (-6775 4575) SIG_NAME GND\g
J 0
(-6765 4585);
DISPLAY 0.659574 (-6765 4585);
PAINT MONO (-6765 4585);
DISPLAY INVISIBLE (-6765 4585);
FORCEPROP 2 LAST CDS_LIB pure_quanta_power
J 0
(-6775 4525);
DISPLAY INVISIBLE (-6775 4525);
FORCEPROP 1 LAST SIZE 1B
J 0
(-6700 4475);
DISPLAY 0.872340 (-6700 4475);
PAINT GREEN (-6700 4475);
DISPLAY INVISIBLE (-6700 4475);
FORCEPROP 1 LAST HDL_POWER GND
J 0
(-6775 4675);
DISPLAY 0.872340 (-6775 4675);
PAINT GREEN (-6775 4675);
DISPLAY INVISIBLE (-6775 4675);
FORCEPROP 1 LAST PATH I33
J 0
(-6700 4525);
DISPLAY 0.872340 (-6700 4525);
PAINT AQUA (-6700 4525);
DISPLAY INVISIBLE (-6700 4525);
FORCEADD Q_CAP..1
(-7225 4925);
FORCEPROP 1 LAST LOCATION C6033
J 0
(-7175 5025);
DISPLAY 0.638298 (-7175 5025);
FORCEPROP 0 LAST $SEC 1
J 0
(-7175 5075);
DISPLAY 0.680851 (-7175 5075);
PAINT MONO (-7175 5075);
DISPLAY INVISIBLE (-7175 5075);
FORCEPROP 0 LAST CDS_SEC 1
J 0
(-7175 5075);
DISPLAY 0.680851 (-7175 5075);
DISPLAY INVISIBLE (-7175 5075);
FORCEPROP 1 LASTPIN (-7225 5025) $PN 1
J 0
(-7215 5005);
DISPLAY 0.787234 (-7215 5005);
PAINT MONO (-7215 5005);
FORCEPROP 1 LASTPIN (-7225 4825) $PN 2
J 0
(-7215 4805);
DISPLAY 0.787234 (-7215 4805);
PAINT MONO (-7215 4805);
FORCEPROP 1 LAST VALUE 0.01UF
J 0
(-7175 4975);
DISPLAY 0.510638 (-7175 4975);
FORCEPROP 1 LAST MATERIAL X7R
J 0
(-7175 4825);
DISPLAY 0.510638 (-7175 4825);
FORCEPROP 1 LAST TOLERANCE 10%
J 0
(-7175 4875);
DISPLAY 0.510638 (-7175 4875);
FORCEPROP 2 LAST ROOM USB3_HUB1_CYP
J 0
(-7200 4775);
DISPLAY 0.361702 (-7200 4775);
PAINT RED (-7200 4775);
FORCEPROP 1 LAST PACK_TYPE C0402
J 0
(-7175 4725);
DISPLAY 0.510638 (-7175 4725);
FORCEPROP 1 LAST VOLTAGE 50V
J 0
(-7175 4925);
DISPLAY 0.510638 (-7175 4925);
FORCEPROP 2 LAST CDS_LIB pure_quanta
J 0
(-7225 4925);
DISPLAY INVISIBLE (-7225 4925);
FORCEPROP 1 LAST PATH I34
J 0
(-7175 5075);
DISPLAY 0.978723 (-7175 5075);
PAINT WHITE (-7175 5075);
DISPLAY INVISIBLE (-7175 5075);
FORCEPROP 1 LAST PART_NUMBER CH31006KB18
J 0
(-7175 4775);
DISPLAY 0.404255 (-7175 4775);
DISPLAY INVISIBLE (-7175 4775);
FORCEADD Q_CAP..1
(-7475 4925);
FORCEPROP 1 LAST LOCATION C6032
J 0
(-7425 5025);
DISPLAY 0.638298 (-7425 5025);
FORCEPROP 0 LAST $SEC 1
J 0
(-7425 5075);
DISPLAY 0.680851 (-7425 5075);
PAINT MONO (-7425 5075);
DISPLAY INVISIBLE (-7425 5075);
FORCEPROP 0 LAST CDS_SEC 1
J 0
(-7425 5075);
DISPLAY 0.680851 (-7425 5075);
DISPLAY INVISIBLE (-7425 5075);
FORCEPROP 1 LASTPIN (-7475 5025) $PN 1
J 0
(-7465 5005);
DISPLAY 0.787234 (-7465 5005);
PAINT MONO (-7465 5005);
FORCEPROP 1 LASTPIN (-7475 4825) $PN 2
J 0
(-7465 4805);
DISPLAY 0.787234 (-7465 4805);
PAINT MONO (-7465 4805);
FORCEPROP 1 LAST VOLTAGE 25V
J 0
(-7425 4925);
DISPLAY 0.638298 (-7425 4925);
FORCEPROP 1 LAST TOLERANCE 10%
J 0
(-7425 4875);
DISPLAY 0.638298 (-7425 4875);
FORCEPROP 1 LAST PACK_TYPE 0402
J 0
(-7425 4725);
DISPLAY 0.638298 (-7425 4725);
FORCEPROP 1 LAST MATERIAL X7R
J 0
(-7425 4825);
DISPLAY 0.638298 (-7425 4825);
FORCEPROP 2 LAST ROOM USB3_HUB1_CYP
J 0
(-7450 4775);
DISPLAY 0.361702 (-7450 4775);
PAINT RED (-7450 4775);
FORCEPROP 1 LAST VALUE 0.1UF
J 0
(-7425 4975);
DISPLAY 0.638298 (-7425 4975);
FORCEPROP 2 LAST CDS_LIB pure_quanta
J 0
(-7475 4925);
DISPLAY INVISIBLE (-7475 4925);
FORCEPROP 1 LAST PATH I35
J 0
(-7425 5075);
DISPLAY 0.978723 (-7425 5075);
PAINT WHITE (-7425 5075);
DISPLAY INVISIBLE (-7425 5075);
FORCEPROP 1 LAST PART_NUMBER CH4104K1B00
J 0
(-7425 4775);
DISPLAY 0.808511 (-7425 4775);
DISPLAY INVISIBLE (-7425 4775);
FORCEADD GND..1
(-7475 4575);
FORCEPROP 3 LASTPIN (-7475 4625) SIG_NAME GND\g
J 0
(-7465 4635);
DISPLAY 0.659574 (-7465 4635);
PAINT MONO (-7465 4635);
DISPLAY INVISIBLE (-7465 4635);
FORCEPROP 2 LAST CDS_LIB pure_quanta_power
J 0
(-7475 4575);
DISPLAY INVISIBLE (-7475 4575);
FORCEPROP 1 LAST SIZE 1B
J 0
(-7400 4525);
DISPLAY 0.872340 (-7400 4525);
PAINT GREEN (-7400 4525);
DISPLAY INVISIBLE (-7400 4525);
FORCEPROP 1 LAST HDL_POWER GND
J 0
(-7475 4725);
DISPLAY 0.872340 (-7475 4725);
PAINT GREEN (-7475 4725);
DISPLAY INVISIBLE (-7475 4725);
FORCEPROP 1 LAST PATH I36
J 0
(-7400 4575);
DISPLAY 0.872340 (-7400 4575);
PAINT AQUA (-7400 4575);
DISPLAY INVISIBLE (-7400 4575);
FORCEADD Q_CAP..1
(-6450 4925);
FORCEPROP 1 LAST LOCATION C6036
J 0
(-6400 5025);
DISPLAY 0.638298 (-6400 5025);
FORCEPROP 0 LAST $SEC 1
J 0
(-6400 5075);
DISPLAY 0.680851 (-6400 5075);
PAINT MONO (-6400 5075);
DISPLAY INVISIBLE (-6400 5075);
FORCEPROP 0 LAST CDS_SEC 1
J 0
(-6400 5075);
DISPLAY 0.680851 (-6400 5075);
DISPLAY INVISIBLE (-6400 5075);
FORCEPROP 1 LASTPIN (-6450 5025) $PN 1
J 0
(-6440 5005);
DISPLAY 0.787234 (-6440 5005);
PAINT MONO (-6440 5005);
FORCEPROP 1 LASTPIN (-6450 4825) $PN 2
J 0
(-6440 4805);
DISPLAY 0.787234 (-6440 4805);
PAINT MONO (-6440 4805);
FORCEPROP 1 LAST PACK_TYPE 0402
J 0
(-6400 4725);
DISPLAY 0.510638 (-6400 4725);
FORCEPROP 2 LAST ROOM USB3_HUB1_CYP
J 0
(-6425 4775);
DISPLAY 0.297872 (-6425 4775);
PAINT RED (-6425 4775);
FORCEPROP 1 LAST MATERIAL X7R
J 0
(-6400 4825);
DISPLAY 0.510638 (-6400 4825);
FORCEPROP 1 LAST VOLTAGE 25V
J 0
(-6400 4925);
DISPLAY 0.510638 (-6400 4925);
FORCEPROP 1 LAST TOLERANCE 10%
J 0
(-6400 4875);
DISPLAY 0.510638 (-6400 4875);
FORCEPROP 1 LAST VALUE 0.1UF
J 0
(-6400 4975);
DISPLAY 0.510638 (-6400 4975);
FORCEPROP 2 LAST CDS_LIB pure_quanta
J 0
(-6450 4925);
DISPLAY INVISIBLE (-6450 4925);
FORCEPROP 1 LAST PATH I37
J 0
(-6400 5075);
DISPLAY 0.978723 (-6400 5075);
PAINT WHITE (-6400 5075);
DISPLAY INVISIBLE (-6400 5075);
FORCEPROP 1 LAST PART_NUMBER CH4104K1B00
J 0
(-6400 4775);
DISPLAY 0.808511 (-6400 4775);
DISPLAY INVISIBLE (-6400 4775);
FORCEADD Q_CAP..1
(-6225 4925);
FORCEPROP 1 LAST LOCATION C6037
J 0
(-6175 5025);
DISPLAY 0.638298 (-6175 5025);
FORCEPROP 0 LAST $SEC 1
J 0
(-6175 5075);
DISPLAY 0.680851 (-6175 5075);
PAINT MONO (-6175 5075);
DISPLAY INVISIBLE (-6175 5075);
FORCEPROP 0 LAST CDS_SEC 1
J 0
(-6175 5075);
DISPLAY 0.680851 (-6175 5075);
DISPLAY INVISIBLE (-6175 5075);
FORCEPROP 1 LASTPIN (-6225 5025) $PN 1
J 0
(-6215 5005);
DISPLAY 0.787234 (-6215 5005);
PAINT MONO (-6215 5005);
FORCEPROP 1 LASTPIN (-6225 4825) $PN 2
J 0
(-6215 4805);
DISPLAY 0.787234 (-6215 4805);
PAINT MONO (-6215 4805);
FORCEPROP 1 LAST VOLTAGE 50V
J 0
(-6175 4925);
DISPLAY 0.510638 (-6175 4925);
FORCEPROP 1 LAST VALUE 0.01UF
J 0
(-6175 4975);
DISPLAY 0.510638 (-6175 4975);
FORCEPROP 1 LAST TOLERANCE 10%
J 0
(-6175 4875);
DISPLAY 0.510638 (-6175 4875);
FORCEPROP 1 LAST MATERIAL X7R
J 0
(-6175 4825);
DISPLAY 0.510638 (-6175 4825);
FORCEPROP 1 LAST PACK_TYPE C0402
J 0
(-6175 4725);
DISPLAY 0.510638 (-6175 4725);
FORCEPROP 2 LAST ROOM USB3_HUB1_CYP
J 0
(-6175 4775);
DISPLAY 0.361702 (-6175 4775);
PAINT RED (-6175 4775);
FORCEPROP 2 LAST CDS_LIB pure_quanta
J 0
(-6225 4925);
DISPLAY INVISIBLE (-6225 4925);
FORCEPROP 1 LAST PATH I38
J 0
(-6175 5075);
DISPLAY 0.978723 (-6175 5075);
PAINT WHITE (-6175 5075);
DISPLAY INVISIBLE (-6175 5075);
FORCEPROP 1 LAST PART_NUMBER CH31006KB18
J 0
(-6175 4775);
DISPLAY 0.638298 (-6175 4775);
DISPLAY INVISIBLE (-6175 4775);
FORCEADD GND..1
(-6450 4550);
FORCEPROP 3 LASTPIN (-6450 4600) SIG_NAME GND\g
J 0
(-6440 4610);
DISPLAY 0.659574 (-6440 4610);
PAINT MONO (-6440 4610);
DISPLAY INVISIBLE (-6440 4610);
FORCEPROP 1 LAST SIZE 1B
J 0
(-6375 4500);
DISPLAY 0.872340 (-6375 4500);
PAINT GREEN (-6375 4500);
DISPLAY INVISIBLE (-6375 4500);
FORCEPROP 2 LAST CDS_LIB pure_quanta_power
J 0
(-6450 4550);
DISPLAY INVISIBLE (-6450 4550);
FORCEPROP 1 LAST HDL_POWER GND
J 0
(-6450 4700);
DISPLAY 0.872340 (-6450 4700);
PAINT GREEN (-6450 4700);
DISPLAY INVISIBLE (-6450 4700);
FORCEPROP 1 LAST PATH I39
J 0
(-6375 4550);
DISPLAY 0.872340 (-6375 4550);
PAINT AQUA (-6375 4550);
DISPLAY INVISIBLE (-6375 4550);
FORCEADD UNIVERSAL_POWER..1
(-7525 3875);
FORCEPROP 3 LASTPIN (-7525 3825) SIG_NAME P3V3_AUX_CPU0_USB_AVDD33\g
J 0
(-7515 3835);
DISPLAY 0.659574 (-7515 3835);
PAINT MONO (-7515 3835);
DISPLAY INVISIBLE (-7515 3835);
FORCEPROP 1 LAST HDL_POWER P3V3_AUX_CPU0_USB_AVDD33
J 1
(-7525 3925);
DISPLAY 0.489362 (-7525 3925);
PAINT GREEN (-7525 3925);
FORCEPROP 2 LAST BOM_COST VR_SYSTEM
J 0
(-7525 3975);
DISPLAY 0.617021 (-7525 3975);
PAINT PURPLE (-7525 3975);
DISPLAY INVISIBLE (-7525 3975);
FORCEPROP 2 LAST CDS_LIB pure_quanta_power
J 0
(-7525 3875);
DISPLAY INVISIBLE (-7525 3875);
FORCEPROP 1 LAST PATH I4
J 0
(-7475 3900);
DISPLAY 0.872340 (-7475 3900);
PAINT AQUA (-7475 3900);
DISPLAY INVISIBLE (-7475 3900);
FORCEADD Q_CAP..1
(-5650 4900);
FORCEPROP 1 LAST LOCATION C6039
J 0
(-5600 5000);
DISPLAY 0.978723 (-5600 5000);
FORCEPROP 0 LAST $SEC 1
J 0
(-5600 5050);
DISPLAY 0.680851 (-5600 5050);
PAINT MONO (-5600 5050);
DISPLAY INVISIBLE (-5600 5050);
FORCEPROP 0 LAST CDS_SEC 1
J 0
(-5600 5050);
DISPLAY 0.680851 (-5600 5050);
DISPLAY INVISIBLE (-5600 5050);
FORCEPROP 1 LASTPIN (-5650 5000) $PN 1
J 0
(-5640 4980);
DISPLAY 0.787234 (-5640 4980);
PAINT MONO (-5640 4980);
FORCEPROP 1 LASTPIN (-5650 4800) $PN 2
J 0
(-5640 4780);
DISPLAY 0.787234 (-5640 4780);
PAINT MONO (-5640 4780);
FORCEPROP 1 LAST VOLTAGE 50V
J 0
(-5600 4900);
DISPLAY 0.510638 (-5600 4900);
FORCEPROP 1 LAST TOLERANCE 10%
J 0
(-5600 4850);
DISPLAY 0.510638 (-5600 4850);
FORCEPROP 1 LAST MATERIAL X7R
J 0
(-5600 4800);
DISPLAY 0.510638 (-5600 4800);
FORCEPROP 2 LAST ROOM USB3_HUB1_CYP
J 0
(-5600 4750);
DISPLAY 0.361702 (-5600 4750);
PAINT RED (-5600 4750);
FORCEPROP 1 LAST PACK_TYPE C0402
J 0
(-5600 4700);
DISPLAY 0.510638 (-5600 4700);
FORCEPROP 1 LAST VALUE 0.01UF
J 0
(-5600 4950);
DISPLAY 0.510638 (-5600 4950);
FORCEPROP 2 LAST CDS_LIB pure_quanta
J 0
(-5650 4900);
DISPLAY INVISIBLE (-5650 4900);
FORCEPROP 1 LAST PATH I40
J 0
(-5600 5050);
DISPLAY 0.978723 (-5600 5050);
PAINT WHITE (-5600 5050);
DISPLAY INVISIBLE (-5600 5050);
FORCEPROP 1 LAST PART_NUMBER CH31006KB18
J 0
(-5600 4750);
DISPLAY 0.638298 (-5600 4750);
DISPLAY INVISIBLE (-5600 4750);
FORCEADD Q_CAP..1
(-5875 4900);
FORCEPROP 1 LAST LOCATION C6038
J 0
(-5825 5000);
DISPLAY 0.978723 (-5825 5000);
FORCEPROP 0 LAST $SEC 1
J 0
(-5825 5050);
DISPLAY 0.680851 (-5825 5050);
PAINT MONO (-5825 5050);
DISPLAY INVISIBLE (-5825 5050);
FORCEPROP 0 LAST CDS_SEC 1
J 0
(-5825 5050);
DISPLAY 0.680851 (-5825 5050);
DISPLAY INVISIBLE (-5825 5050);
FORCEPROP 1 LASTPIN (-5875 5000) $PN 1
J 0
(-5865 4980);
DISPLAY 0.787234 (-5865 4980);
PAINT MONO (-5865 4980);
FORCEPROP 1 LASTPIN (-5875 4800) $PN 2
J 0
(-5865 4780);
DISPLAY 0.787234 (-5865 4780);
PAINT MONO (-5865 4780);
FORCEPROP 1 LAST PACK_TYPE 0402
J 0
(-5825 4700);
DISPLAY 0.510638 (-5825 4700);
FORCEPROP 1 LAST VALUE 0.1UF
J 0
(-5825 4950);
DISPLAY 0.510638 (-5825 4950);
FORCEPROP 1 LAST VOLTAGE 25V
J 0
(-5825 4900);
DISPLAY 0.510638 (-5825 4900);
FORCEPROP 1 LAST TOLERANCE 10%
J 0
(-5825 4850);
DISPLAY 0.510638 (-5825 4850);
FORCEPROP 1 LAST MATERIAL X7R
J 0
(-5825 4800);
DISPLAY 0.510638 (-5825 4800);
FORCEPROP 2 LAST ROOM USB3_HUB1_CYP
J 0
(-5850 4750);
DISPLAY 0.297872 (-5850 4750);
PAINT RED (-5850 4750);
FORCEPROP 2 LAST CDS_LIB pure_quanta
J 0
(-5875 4900);
DISPLAY INVISIBLE (-5875 4900);
FORCEPROP 1 LAST PATH I41
J 0
(-5825 5050);
DISPLAY 0.978723 (-5825 5050);
PAINT WHITE (-5825 5050);
DISPLAY INVISIBLE (-5825 5050);
FORCEPROP 1 LAST PART_NUMBER CH4104K1B00
J 0
(-5825 4750);
DISPLAY 0.808511 (-5825 4750);
DISPLAY INVISIBLE (-5825 4750);
FORCEADD GND..1
(-5875 4525);
FORCEPROP 3 LASTPIN (-5875 4575) SIG_NAME GND\g
J 0
(-5865 4585);
DISPLAY 0.659574 (-5865 4585);
PAINT MONO (-5865 4585);
DISPLAY INVISIBLE (-5865 4585);
FORCEPROP 2 LAST CDS_LIB pure_quanta_power
J 0
(-5875 4525);
DISPLAY INVISIBLE (-5875 4525);
FORCEPROP 1 LAST SIZE 1B
J 0
(-5800 4475);
DISPLAY 0.872340 (-5800 4475);
PAINT GREEN (-5800 4475);
DISPLAY INVISIBLE (-5800 4475);
FORCEPROP 1 LAST HDL_POWER GND
J 0
(-5875 4675);
DISPLAY 0.872340 (-5875 4675);
PAINT GREEN (-5875 4675);
DISPLAY INVISIBLE (-5875 4675);
FORCEPROP 1 LAST PATH I42
J 0
(-5800 4525);
DISPLAY 0.872340 (-5800 4525);
PAINT AQUA (-5800 4525);
DISPLAY INVISIBLE (-5800 4525);
FORCEADD Q_CAP..1
(-3750 4850);
FORCEPROP 1 LAST LOCATION C6054
J 0
(-3700 4950);
DISPLAY 0.617021 (-3700 4950);
PAINT SKYBLUE (-3700 4950);
FORCEPROP 0 LAST $SEC 1
J 0
(-3700 5000);
DISPLAY 0.680851 (-3700 5000);
PAINT MONO (-3700 5000);
DISPLAY INVISIBLE (-3700 5000);
FORCEPROP 0 LAST CDS_SEC 1
J 0
(-3700 5000);
DISPLAY 0.680851 (-3700 5000);
DISPLAY INVISIBLE (-3700 5000);
FORCEPROP 1 LASTPIN (-3750 4950) $PN 1
J 0
(-3740 4930);
DISPLAY 0.787234 (-3740 4930);
PAINT MONO (-3740 4930);
FORCEPROP 1 LASTPIN (-3750 4750) $PN 2
J 0
(-3740 4730);
DISPLAY 0.787234 (-3740 4730);
PAINT MONO (-3740 4730);
FORCEPROP 1 LAST PACK_TYPE C0402
J 0
(-3700 4700);
DISPLAY 0.489362 (-3700 4700);
PAINT SKYBLUE (-3700 4700);
FORCEPROP 1 LAST TOLERANCE 10%
J 0
(-3700 4800);
DISPLAY 0.489362 (-3700 4800);
PAINT SKYBLUE (-3700 4800);
FORCEPROP 1 LAST VOLTAGE 50V
J 0
(-3700 4850);
DISPLAY 0.489362 (-3700 4850);
PAINT SKYBLUE (-3700 4850);
FORCEPROP 1 LAST VALUE 0.001UF
J 0
(-3700 4900);
DISPLAY 0.489362 (-3700 4900);
PAINT SKYBLUE (-3700 4900);
FORCEPROP 1 LAST MATERIAL X7R
J 0
(-3700 4750);
DISPLAY 0.489362 (-3700 4750);
PAINT SKYBLUE (-3700 4750);
FORCEPROP 2 LAST ROOM USB3_HUB1_CYP
J 0
(-3725 4675);
DISPLAY 0.361702 (-3725 4675);
PAINT RED (-3725 4675);
FORCEPROP 2 LAST CDS_LIB pure_quanta
J 0
(-3750 4850);
DISPLAY INVISIBLE (-3750 4850);
FORCEPROP 1 LAST PATH I43
J 0
(-3700 5000);
DISPLAY 0.978723 (-3700 5000);
PAINT WHITE (-3700 5000);
DISPLAY INVISIBLE (-3700 5000);
FORCEPROP 1 LAST PART_NUMBER CH30106KB19
J 0
(-3700 4750);
DISPLAY 0.808511 (-3700 4750);
PAINT SKYBLUE (-3700 4750);
DISPLAY INVISIBLE (-3700 4750);
FORCEADD Q_CAP..1
(-3500 4850);
FORCEPROP 1 LAST LOCATION C6055
J 0
(-3450 4950);
DISPLAY 0.978723 (-3450 4950);
FORCEPROP 0 LAST $SEC 1
J 0
(-3450 5000);
DISPLAY 0.680851 (-3450 5000);
PAINT MONO (-3450 5000);
DISPLAY INVISIBLE (-3450 5000);
FORCEPROP 0 LAST CDS_SEC 1
J 0
(-3450 5000);
DISPLAY 0.680851 (-3450 5000);
DISPLAY INVISIBLE (-3450 5000);
FORCEPROP 1 LASTPIN (-3500 4950) $PN 1
J 0
(-3490 4930);
DISPLAY 0.787234 (-3490 4930);
PAINT MONO (-3490 4930);
FORCEPROP 1 LASTPIN (-3500 4750) $PN 2
J 0
(-3490 4730);
DISPLAY 0.787234 (-3490 4730);
PAINT MONO (-3490 4730);
FORCEPROP 1 LAST PACK_TYPE C0402
J 0
(-3450 4650);
DISPLAY 0.510638 (-3450 4650);
FORCEPROP 1 LAST TOLERANCE 10%
J 0
(-3450 4800);
DISPLAY 0.510638 (-3450 4800);
FORCEPROP 1 LAST MATERIAL X7R
J 0
(-3450 4750);
DISPLAY 0.510638 (-3450 4750);
FORCEPROP 1 LAST VOLTAGE 50V
J 0
(-3450 4850);
DISPLAY 0.510638 (-3450 4850);
FORCEPROP 1 LAST VALUE 0.01UF
J 0
(-3450 4900);
DISPLAY 0.510638 (-3450 4900);
FORCEPROP 2 LAST ROOM USB3_HUB1_CYP
J 0
(-3475 4700);
DISPLAY 0.297872 (-3475 4700);
PAINT RED (-3475 4700);
FORCEPROP 2 LAST CDS_LIB pure_quanta
J 0
(-3500 4850);
DISPLAY INVISIBLE (-3500 4850);
FORCEPROP 1 LAST PATH I44
J 0
(-3450 5000);
DISPLAY 0.978723 (-3450 5000);
PAINT WHITE (-3450 5000);
DISPLAY INVISIBLE (-3450 5000);
FORCEPROP 1 LAST PART_NUMBER CH31006KB18
J 0
(-3450 4700);
DISPLAY 0.638298 (-3450 4700);
DISPLAY INVISIBLE (-3450 4700);
FORCEADD GND..1
(-3700 4525);
FORCEPROP 3 LASTPIN (-3700 4575) SIG_NAME GND\g
J 0
(-3690 4585);
DISPLAY 0.659574 (-3690 4585);
PAINT MONO (-3690 4585);
DISPLAY INVISIBLE (-3690 4585);
FORCEPROP 1 LAST SIZE 1B
J 0
(-3625 4475);
DISPLAY 0.872340 (-3625 4475);
PAINT GREEN (-3625 4475);
DISPLAY INVISIBLE (-3625 4475);
FORCEPROP 2 LAST CDS_LIB pure_quanta_power
J 0
(-3700 4525);
DISPLAY INVISIBLE (-3700 4525);
FORCEPROP 1 LAST HDL_POWER GND
J 0
(-3700 4675);
DISPLAY 0.872340 (-3700 4675);
PAINT GREEN (-3700 4675);
DISPLAY INVISIBLE (-3700 4675);
FORCEPROP 1 LAST PATH I45
J 0
(-3625 4525);
DISPLAY 0.872340 (-3625 4525);
PAINT AQUA (-3625 4525);
DISPLAY INVISIBLE (-3625 4525);
FORCEADD Q_CAP..1
(-3250 4850);
FORCEPROP 1 LAST LOCATION C6056
J 0
(-3200 4950);
DISPLAY 0.617021 (-3200 4950);
PAINT SKYBLUE (-3200 4950);
FORCEPROP 0 LAST $SEC 1
J 0
(-3200 5000);
DISPLAY 0.680851 (-3200 5000);
PAINT MONO (-3200 5000);
DISPLAY INVISIBLE (-3200 5000);
FORCEPROP 0 LAST CDS_SEC 1
J 0
(-3200 5000);
DISPLAY 0.680851 (-3200 5000);
DISPLAY INVISIBLE (-3200 5000);
FORCEPROP 1 LASTPIN (-3250 4950) $PN 1
J 0
(-3240 4930);
DISPLAY 0.787234 (-3240 4930);
PAINT MONO (-3240 4930);
FORCEPROP 1 LASTPIN (-3250 4750) $PN 2
J 0
(-3240 4730);
DISPLAY 0.787234 (-3240 4730);
PAINT MONO (-3240 4730);
FORCEPROP 1 LAST MATERIAL X7R
J 0
(-3200 4750);
DISPLAY 0.489362 (-3200 4750);
PAINT SKYBLUE (-3200 4750);
FORCEPROP 1 LAST TOLERANCE 10%
J 0
(-3200 4800);
DISPLAY 0.489362 (-3200 4800);
PAINT SKYBLUE (-3200 4800);
FORCEPROP 1 LAST PACK_TYPE C0402
J 0
(-3200 4700);
DISPLAY 0.489362 (-3200 4700);
PAINT SKYBLUE (-3200 4700);
FORCEPROP 1 LAST VALUE 0.001UF
J 0
(-3200 4900);
DISPLAY 0.489362 (-3200 4900);
PAINT SKYBLUE (-3200 4900);
FORCEPROP 1 LAST VOLTAGE 50V
J 0
(-3200 4850);
DISPLAY 0.489362 (-3200 4850);
PAINT SKYBLUE (-3200 4850);
FORCEPROP 2 LAST ROOM USB3_HUB1_CYP
J 0
(-3200 4675);
DISPLAY 0.297872 (-3200 4675);
PAINT RED (-3200 4675);
FORCEPROP 2 LAST CDS_LIB pure_quanta
J 0
(-3250 4850);
DISPLAY INVISIBLE (-3250 4850);
FORCEPROP 1 LAST PATH I46
J 0
(-3200 5000);
DISPLAY 0.978723 (-3200 5000);
PAINT WHITE (-3200 5000);
DISPLAY INVISIBLE (-3200 5000);
FORCEPROP 1 LAST PART_NUMBER CH30106KB19
J 0
(-3200 4750);
DISPLAY 0.808511 (-3200 4750);
PAINT SKYBLUE (-3200 4750);
DISPLAY INVISIBLE (-3200 4750);
FORCEADD Q_CAP..1
(-3000 4850);
FORCEPROP 1 LAST LOCATION C6057
J 0
(-2950 4950);
DISPLAY 0.978723 (-2950 4950);
FORCEPROP 0 LAST $SEC 1
J 0
(-2950 5000);
DISPLAY 0.680851 (-2950 5000);
PAINT MONO (-2950 5000);
DISPLAY INVISIBLE (-2950 5000);
FORCEPROP 0 LAST CDS_SEC 1
J 0
(-2950 5000);
DISPLAY 0.680851 (-2950 5000);
DISPLAY INVISIBLE (-2950 5000);
FORCEPROP 1 LASTPIN (-3000 4950) $PN 1
J 0
(-2990 4930);
DISPLAY 0.787234 (-2990 4930);
PAINT MONO (-2990 4930);
FORCEPROP 1 LASTPIN (-3000 4750) $PN 2
J 0
(-2990 4730);
DISPLAY 0.787234 (-2990 4730);
PAINT MONO (-2990 4730);
FORCEPROP 1 LAST TOLERANCE 10%
J 0
(-2950 4800);
DISPLAY 0.510638 (-2950 4800);
FORCEPROP 1 LAST PACK_TYPE C0402
J 0
(-2950 4650);
DISPLAY 0.510638 (-2950 4650);
FORCEPROP 1 LAST VOLTAGE 50V
J 0
(-2950 4850);
DISPLAY 0.510638 (-2950 4850);
FORCEPROP 1 LAST MATERIAL X7R
J 0
(-2950 4750);
DISPLAY 0.510638 (-2950 4750);
FORCEPROP 2 LAST ROOM USB3_HUB1_CYP
J 0
(-2950 4700);
DISPLAY 0.361702 (-2950 4700);
PAINT RED (-2950 4700);
FORCEPROP 1 LAST VALUE 0.01UF
J 0
(-2950 4900);
DISPLAY 0.510638 (-2950 4900);
FORCEPROP 2 LAST CDS_LIB pure_quanta
J 0
(-3000 4850);
DISPLAY INVISIBLE (-3000 4850);
FORCEPROP 1 LAST PATH I47
J 0
(-2950 5000);
DISPLAY 0.978723 (-2950 5000);
PAINT WHITE (-2950 5000);
DISPLAY INVISIBLE (-2950 5000);
FORCEPROP 1 LAST PART_NUMBER CH31006KB18
J 0
(-2950 4700);
DISPLAY 0.638298 (-2950 4700);
DISPLAY INVISIBLE (-2950 4700);
FORCEADD GND..1
(-3200 4525);
FORCEPROP 3 LASTPIN (-3200 4575) SIG_NAME GND\g
J 0
(-3190 4585);
DISPLAY 0.659574 (-3190 4585);
PAINT MONO (-3190 4585);
DISPLAY INVISIBLE (-3190 4585);
FORCEPROP 1 LAST SIZE 1B
J 0
(-3125 4475);
DISPLAY 0.872340 (-3125 4475);
PAINT GREEN (-3125 4475);
DISPLAY INVISIBLE (-3125 4475);
FORCEPROP 2 LAST CDS_LIB pure_quanta_power
J 0
(-3200 4525);
DISPLAY INVISIBLE (-3200 4525);
FORCEPROP 1 LAST HDL_POWER GND
J 0
(-3200 4675);
DISPLAY 0.872340 (-3200 4675);
PAINT GREEN (-3200 4675);
DISPLAY INVISIBLE (-3200 4675);
FORCEPROP 1 LAST PATH I48
J 0
(-3125 4525);
DISPLAY 0.872340 (-3125 4525);
PAINT AQUA (-3125 4525);
DISPLAY INVISIBLE (-3125 4525);
FORCEADD Q_CAP..1
(-2650 4850);
FORCEPROP 1 LAST LOCATION C6058
J 0
(-2600 4950);
DISPLAY 0.617021 (-2600 4950);
PAINT SKYBLUE (-2600 4950);
FORCEPROP 0 LAST $SEC 1
J 0
(-2600 5000);
DISPLAY 0.680851 (-2600 5000);
PAINT MONO (-2600 5000);
DISPLAY INVISIBLE (-2600 5000);
FORCEPROP 0 LAST CDS_SEC 1
J 0
(-2600 5000);
DISPLAY 0.680851 (-2600 5000);
DISPLAY INVISIBLE (-2600 5000);
FORCEPROP 1 LASTPIN (-2650 4950) $PN 1
J 0
(-2640 4930);
DISPLAY 0.787234 (-2640 4930);
PAINT MONO (-2640 4930);
FORCEPROP 1 LASTPIN (-2650 4750) $PN 2
J 0
(-2640 4730);
DISPLAY 0.787234 (-2640 4730);
PAINT MONO (-2640 4730);
FORCEPROP 1 LAST VALUE 0.001UF
J 0
(-2600 4900);
DISPLAY 0.489362 (-2600 4900);
PAINT SKYBLUE (-2600 4900);
FORCEPROP 1 LAST VOLTAGE 50V
J 0
(-2600 4850);
DISPLAY 0.489362 (-2600 4850);
PAINT SKYBLUE (-2600 4850);
FORCEPROP 1 LAST MATERIAL X7R
J 0
(-2600 4750);
DISPLAY 0.489362 (-2600 4750);
PAINT SKYBLUE (-2600 4750);
FORCEPROP 1 LAST TOLERANCE 10%
J 0
(-2600 4800);
DISPLAY 0.489362 (-2600 4800);
PAINT SKYBLUE (-2600 4800);
FORCEPROP 1 LAST PACK_TYPE C0402
J 0
(-2600 4700);
DISPLAY 0.489362 (-2600 4700);
PAINT SKYBLUE (-2600 4700);
FORCEPROP 2 LAST ROOM USB3_HUB1_CYP
J 0
(-2600 4650);
DISPLAY 0.297872 (-2600 4650);
PAINT RED (-2600 4650);
FORCEPROP 2 LAST CDS_LIB pure_quanta
J 0
(-2650 4850);
DISPLAY INVISIBLE (-2650 4850);
FORCEPROP 1 LAST PATH I49
J 0
(-2600 5000);
DISPLAY 0.978723 (-2600 5000);
PAINT WHITE (-2600 5000);
DISPLAY INVISIBLE (-2600 5000);
FORCEPROP 1 LAST PART_NUMBER CH30106KB19
J 0
(-2600 4750);
DISPLAY 0.808511 (-2600 4750);
PAINT SKYBLUE (-2600 4750);
DISPLAY INVISIBLE (-2600 4750);
FORCEADD Q_CAP..1
(-6850 3900);
FORCEPROP 1 LAST LOCATION C6040
J 0
(-6800 4000);
DISPLAY 0.787234 (-6800 4000);
FORCEPROP 0 LAST $SEC 1
J 0
(-6800 4050);
DISPLAY 0.680851 (-6800 4050);
PAINT MONO (-6800 4050);
DISPLAY INVISIBLE (-6800 4050);
FORCEPROP 0 LAST CDS_SEC 1
J 0
(-6800 4050);
DISPLAY 0.680851 (-6800 4050);
DISPLAY INVISIBLE (-6800 4050);
FORCEPROP 1 LASTPIN (-6850 4000) $PN 1
J 0
(-6840 3980);
DISPLAY 0.787234 (-6840 3980);
PAINT MONO (-6840 3980);
FORCEPROP 1 LASTPIN (-6850 3800) $PN 2
J 0
(-6840 3780);
DISPLAY 0.787234 (-6840 3780);
PAINT MONO (-6840 3780);
FORCEPROP 1 LAST PACK_TYPE C0402
J 0
(-6800 3700);
DISPLAY 0.787234 (-6800 3700);
FORCEPROP 1 LAST VOLTAGE 50V
J 0
(-6800 3900);
DISPLAY 0.787234 (-6800 3900);
FORCEPROP 1 LAST TOLERANCE 10%
J 0
(-6800 3850);
DISPLAY 0.787234 (-6800 3850);
FORCEPROP 1 LAST VALUE 0.01UF
J 0
(-6800 3950);
DISPLAY 0.787234 (-6800 3950);
FORCEPROP 2 LAST ROOM USB3_HUB1_CYP
J 0
(-6800 4050);
DISPLAY 0.553191 (-6800 4050);
PAINT RED (-6800 4050);
FORCEPROP 1 LAST MATERIAL X7R
J 0
(-6800 3800);
DISPLAY 0.787234 (-6800 3800);
FORCEPROP 2 LAST CDS_LIB pure_quanta
J 0
(-6850 3900);
DISPLAY INVISIBLE (-6850 3900);
FORCEPROP 1 LAST PATH I5
J 0
(-6800 4050);
DISPLAY 0.978723 (-6800 4050);
PAINT WHITE (-6800 4050);
DISPLAY INVISIBLE (-6800 4050);
FORCEPROP 1 LAST PART_NUMBER CH31006KB18
J 0
(-6800 3750);
DISPLAY 0.638298 (-6800 3750);
DISPLAY INVISIBLE (-6800 3750);
FORCEADD Q_CAP..1
(-2400 4850);
FORCEPROP 1 LAST LOCATION C6059
J 0
(-2350 4950);
DISPLAY 0.978723 (-2350 4950);
FORCEPROP 0 LAST $SEC 1
J 0
(-2350 5000);
DISPLAY 0.680851 (-2350 5000);
PAINT MONO (-2350 5000);
DISPLAY INVISIBLE (-2350 5000);
FORCEPROP 0 LAST CDS_SEC 1
J 0
(-2350 5000);
DISPLAY 0.680851 (-2350 5000);
DISPLAY INVISIBLE (-2350 5000);
FORCEPROP 1 LASTPIN (-2400 4950) $PN 1
J 0
(-2390 4930);
DISPLAY 0.787234 (-2390 4930);
PAINT MONO (-2390 4930);
FORCEPROP 1 LASTPIN (-2400 4750) $PN 2
J 0
(-2390 4730);
DISPLAY 0.787234 (-2390 4730);
PAINT MONO (-2390 4730);
FORCEPROP 1 LAST MATERIAL X7R
J 0
(-2350 4750);
DISPLAY 0.510638 (-2350 4750);
FORCEPROP 1 LAST PACK_TYPE C0402
J 0
(-2350 4650);
DISPLAY 0.510638 (-2350 4650);
FORCEPROP 1 LAST VALUE 0.01UF
J 0
(-2350 4900);
DISPLAY 0.510638 (-2350 4900);
FORCEPROP 1 LAST TOLERANCE 10%
J 0
(-2350 4800);
DISPLAY 0.510638 (-2350 4800);
FORCEPROP 1 LAST VOLTAGE 50V
J 0
(-2350 4850);
DISPLAY 0.510638 (-2350 4850);
FORCEPROP 2 LAST ROOM USB3_HUB1_CYP
J 0
(-2350 4700);
DISPLAY 0.446809 (-2350 4700);
PAINT RED (-2350 4700);
FORCEPROP 2 LAST CDS_LIB pure_quanta
J 0
(-2400 4850);
DISPLAY INVISIBLE (-2400 4850);
FORCEPROP 1 LAST PATH I50
J 0
(-2350 5000);
DISPLAY 0.978723 (-2350 5000);
PAINT WHITE (-2350 5000);
DISPLAY INVISIBLE (-2350 5000);
FORCEPROP 1 LAST PART_NUMBER CH31006KB18
J 0
(-2350 4700);
DISPLAY 0.638298 (-2350 4700);
DISPLAY INVISIBLE (-2350 4700);
FORCEADD GND..1
(-2600 4525);
FORCEPROP 3 LASTPIN (-2600 4575) SIG_NAME GND\g
J 0
(-2590 4585);
DISPLAY 0.659574 (-2590 4585);
PAINT MONO (-2590 4585);
DISPLAY INVISIBLE (-2590 4585);
FORCEPROP 1 LAST SIZE 1B
J 0
(-2525 4475);
DISPLAY 0.872340 (-2525 4475);
PAINT GREEN (-2525 4475);
DISPLAY INVISIBLE (-2525 4475);
FORCEPROP 2 LAST CDS_LIB pure_quanta_power
J 0
(-2600 4525);
DISPLAY INVISIBLE (-2600 4525);
FORCEPROP 1 LAST HDL_POWER GND
J 0
(-2600 4675);
DISPLAY 0.872340 (-2600 4675);
PAINT GREEN (-2600 4675);
DISPLAY INVISIBLE (-2600 4675);
FORCEPROP 1 LAST PATH I51
J 0
(-2525 4525);
DISPLAY 0.872340 (-2525 4525);
PAINT AQUA (-2525 4525);
DISPLAY INVISIBLE (-2525 4525);
FORCEADD Q_CAP..1
(-2025 4850);
FORCEPROP 1 LAST LOCATION C6060
J 0
(-1975 4950);
DISPLAY 0.617021 (-1975 4950);
PAINT SKYBLUE (-1975 4950);
FORCEPROP 0 LAST $SEC 1
J 0
(-1975 5000);
DISPLAY 0.680851 (-1975 5000);
PAINT MONO (-1975 5000);
DISPLAY INVISIBLE (-1975 5000);
FORCEPROP 0 LAST CDS_SEC 1
J 0
(-1975 5000);
DISPLAY 0.680851 (-1975 5000);
DISPLAY INVISIBLE (-1975 5000);
FORCEPROP 1 LASTPIN (-2025 4950) $PN 1
J 0
(-2015 4930);
DISPLAY 0.787234 (-2015 4930);
PAINT MONO (-2015 4930);
FORCEPROP 1 LASTPIN (-2025 4750) $PN 2
J 0
(-2015 4730);
DISPLAY 0.787234 (-2015 4730);
PAINT MONO (-2015 4730);
FORCEPROP 1 LAST VALUE 0.001UF
J 0
(-1975 4900);
DISPLAY 0.489362 (-1975 4900);
PAINT SKYBLUE (-1975 4900);
FORCEPROP 1 LAST VOLTAGE 50V
J 0
(-1975 4850);
DISPLAY 0.489362 (-1975 4850);
PAINT SKYBLUE (-1975 4850);
FORCEPROP 1 LAST TOLERANCE 10%
J 0
(-1975 4800);
DISPLAY 0.489362 (-1975 4800);
PAINT SKYBLUE (-1975 4800);
FORCEPROP 1 LAST MATERIAL X7R
J 0
(-1975 4750);
DISPLAY 0.489362 (-1975 4750);
PAINT SKYBLUE (-1975 4750);
FORCEPROP 1 LAST PACK_TYPE C0402
J 0
(-1975 4700);
DISPLAY 0.489362 (-1975 4700);
PAINT SKYBLUE (-1975 4700);
FORCEPROP 2 LAST ROOM USB3_HUB1_CYP
J 0
(-1975 4650);
DISPLAY 0.297872 (-1975 4650);
PAINT RED (-1975 4650);
FORCEPROP 2 LAST CDS_LIB pure_quanta
J 0
(-2025 4850);
DISPLAY INVISIBLE (-2025 4850);
FORCEPROP 1 LAST PATH I52
J 0
(-1975 5000);
DISPLAY 0.978723 (-1975 5000);
PAINT WHITE (-1975 5000);
DISPLAY INVISIBLE (-1975 5000);
FORCEPROP 1 LAST PART_NUMBER CH30106KB19
J 0
(-1975 4750);
DISPLAY 0.808511 (-1975 4750);
PAINT SKYBLUE (-1975 4750);
DISPLAY INVISIBLE (-1975 4750);
FORCEADD Q_CAP..1
(-1775 4850);
FORCEPROP 1 LAST LOCATION C6061
J 0
(-1725 4950);
DISPLAY 0.978723 (-1725 4950);
FORCEPROP 0 LAST $SEC 1
J 0
(-1725 5000);
DISPLAY 0.680851 (-1725 5000);
PAINT MONO (-1725 5000);
DISPLAY INVISIBLE (-1725 5000);
FORCEPROP 0 LAST CDS_SEC 1
J 0
(-1725 5000);
DISPLAY 0.680851 (-1725 5000);
DISPLAY INVISIBLE (-1725 5000);
FORCEPROP 1 LASTPIN (-1775 4950) $PN 1
J 0
(-1765 4930);
DISPLAY 0.787234 (-1765 4930);
PAINT MONO (-1765 4930);
FORCEPROP 1 LASTPIN (-1775 4750) $PN 2
J 0
(-1765 4730);
DISPLAY 0.787234 (-1765 4730);
PAINT MONO (-1765 4730);
FORCEPROP 2 LAST ROOM USB3_HUB1_CYP
J 0
(-1725 4700);
DISPLAY 0.361702 (-1725 4700);
PAINT RED (-1725 4700);
FORCEPROP 1 LAST PACK_TYPE C0402
J 0
(-1725 4650);
DISPLAY 0.510638 (-1725 4650);
FORCEPROP 1 LAST VALUE 0.01UF
J 0
(-1725 4900);
DISPLAY 0.510638 (-1725 4900);
FORCEPROP 1 LAST VOLTAGE 50V
J 0
(-1725 4850);
DISPLAY 0.510638 (-1725 4850);
FORCEPROP 1 LAST TOLERANCE 10%
J 0
(-1725 4800);
DISPLAY 0.510638 (-1725 4800);
FORCEPROP 1 LAST MATERIAL X7R
J 0
(-1725 4750);
DISPLAY 0.510638 (-1725 4750);
FORCEPROP 2 LAST CDS_LIB pure_quanta
J 0
(-1775 4850);
DISPLAY INVISIBLE (-1775 4850);
FORCEPROP 1 LAST PATH I53
J 0
(-1725 5000);
DISPLAY 0.978723 (-1725 5000);
PAINT WHITE (-1725 5000);
DISPLAY INVISIBLE (-1725 5000);
FORCEPROP 1 LAST PART_NUMBER CH31006KB18
J 0
(-1725 4700);
DISPLAY 0.638298 (-1725 4700);
DISPLAY INVISIBLE (-1725 4700);
FORCEADD GND..1
(-1975 4525);
FORCEPROP 3 LASTPIN (-1975 4575) SIG_NAME GND\g
J 0
(-1965 4585);
DISPLAY 0.659574 (-1965 4585);
PAINT MONO (-1965 4585);
DISPLAY INVISIBLE (-1965 4585);
FORCEPROP 1 LAST SIZE 1B
J 0
(-1900 4475);
DISPLAY 0.872340 (-1900 4475);
PAINT GREEN (-1900 4475);
DISPLAY INVISIBLE (-1900 4475);
FORCEPROP 2 LAST CDS_LIB pure_quanta_power
J 0
(-1975 4525);
DISPLAY INVISIBLE (-1975 4525);
FORCEPROP 1 LAST HDL_POWER GND
J 0
(-1975 4675);
DISPLAY 0.872340 (-1975 4675);
PAINT GREEN (-1975 4675);
DISPLAY INVISIBLE (-1975 4675);
FORCEPROP 1 LAST PATH I54
J 0
(-1900 4525);
DISPLAY 0.872340 (-1900 4525);
PAINT AQUA (-1900 4525);
DISPLAY INVISIBLE (-1900 4525);
FORCEADD Q_CAP..1
(-1425 4850);
FORCEPROP 1 LAST LOCATION C6062
J 0
(-1375 4950);
DISPLAY 0.617021 (-1375 4950);
PAINT SKYBLUE (-1375 4950);
FORCEPROP 0 LAST $SEC 1
J 0
(-1375 5000);
DISPLAY 0.680851 (-1375 5000);
PAINT MONO (-1375 5000);
DISPLAY INVISIBLE (-1375 5000);
FORCEPROP 0 LAST CDS_SEC 1
J 0
(-1375 5000);
DISPLAY 0.680851 (-1375 5000);
DISPLAY INVISIBLE (-1375 5000);
FORCEPROP 1 LASTPIN (-1425 4950) $PN 1
J 0
(-1415 4930);
DISPLAY 0.787234 (-1415 4930);
PAINT MONO (-1415 4930);
FORCEPROP 1 LASTPIN (-1425 4750) $PN 2
J 0
(-1415 4730);
DISPLAY 0.787234 (-1415 4730);
PAINT MONO (-1415 4730);
FORCEPROP 2 LAST ROOM USB3_HUB1_CYP
J 0
(-1375 4650);
DISPLAY 0.297872 (-1375 4650);
PAINT RED (-1375 4650);
FORCEPROP 1 LAST TOLERANCE 10%
J 0
(-1375 4800);
DISPLAY 0.489362 (-1375 4800);
PAINT SKYBLUE (-1375 4800);
FORCEPROP 1 LAST VOLTAGE 50V
J 0
(-1375 4850);
DISPLAY 0.489362 (-1375 4850);
PAINT SKYBLUE (-1375 4850);
FORCEPROP 1 LAST MATERIAL X7R
J 0
(-1375 4750);
DISPLAY 0.489362 (-1375 4750);
PAINT SKYBLUE (-1375 4750);
FORCEPROP 1 LAST PACK_TYPE C0402
J 0
(-1375 4700);
DISPLAY 0.489362 (-1375 4700);
PAINT SKYBLUE (-1375 4700);
FORCEPROP 1 LAST VALUE 0.001UF
J 0
(-1375 4900);
DISPLAY 0.489362 (-1375 4900);
PAINT SKYBLUE (-1375 4900);
FORCEPROP 2 LAST CDS_LIB pure_quanta
J 0
(-1425 4850);
DISPLAY INVISIBLE (-1425 4850);
FORCEPROP 1 LAST PATH I55
J 0
(-1375 5000);
DISPLAY 0.978723 (-1375 5000);
PAINT WHITE (-1375 5000);
DISPLAY INVISIBLE (-1375 5000);
FORCEPROP 1 LAST PART_NUMBER CH30106KB19
J 0
(-1375 4750);
DISPLAY 0.808511 (-1375 4750);
PAINT SKYBLUE (-1375 4750);
DISPLAY INVISIBLE (-1375 4750);
FORCEADD Q_CAP..1
(-1175 4850);
FORCEPROP 1 LAST LOCATION C6063
J 0
(-1125 4950);
DISPLAY 0.978723 (-1125 4950);
FORCEPROP 0 LAST $SEC 1
J 0
(-1125 5000);
DISPLAY 0.680851 (-1125 5000);
PAINT MONO (-1125 5000);
DISPLAY INVISIBLE (-1125 5000);
FORCEPROP 0 LAST CDS_SEC 1
J 0
(-1125 5000);
DISPLAY 0.680851 (-1125 5000);
DISPLAY INVISIBLE (-1125 5000);
FORCEPROP 1 LASTPIN (-1175 4950) $PN 1
J 0
(-1165 4930);
DISPLAY 0.787234 (-1165 4930);
PAINT MONO (-1165 4930);
FORCEPROP 1 LASTPIN (-1175 4750) $PN 2
J 0
(-1165 4730);
DISPLAY 0.787234 (-1165 4730);
PAINT MONO (-1165 4730);
FORCEPROP 2 LAST ROOM USB3_HUB1_CYP
J 0
(-1125 4700);
DISPLAY 0.446809 (-1125 4700);
PAINT RED (-1125 4700);
FORCEPROP 1 LAST PACK_TYPE C0402
J 0
(-1125 4650);
DISPLAY 0.510638 (-1125 4650);
FORCEPROP 1 LAST VALUE 0.01UF
J 0
(-1125 4900);
DISPLAY 0.510638 (-1125 4900);
FORCEPROP 1 LAST VOLTAGE 50V
J 0
(-1125 4850);
DISPLAY 0.510638 (-1125 4850);
FORCEPROP 1 LAST TOLERANCE 10%
J 0
(-1125 4800);
DISPLAY 0.510638 (-1125 4800);
FORCEPROP 1 LAST MATERIAL X7R
J 0
(-1125 4750);
DISPLAY 0.510638 (-1125 4750);
FORCEPROP 2 LAST CDS_LIB pure_quanta
J 0
(-1175 4850);
DISPLAY INVISIBLE (-1175 4850);
FORCEPROP 1 LAST PATH I56
J 0
(-1125 5000);
DISPLAY 0.978723 (-1125 5000);
PAINT WHITE (-1125 5000);
DISPLAY INVISIBLE (-1125 5000);
FORCEPROP 1 LAST PART_NUMBER CH31006KB18
J 0
(-1125 4700);
DISPLAY 0.638298 (-1125 4700);
DISPLAY INVISIBLE (-1125 4700);
FORCEADD GND..1
(-1375 4525);
FORCEPROP 3 LASTPIN (-1375 4575) SIG_NAME GND\g
J 0
(-1365 4585);
DISPLAY 0.659574 (-1365 4585);
PAINT MONO (-1365 4585);
DISPLAY INVISIBLE (-1365 4585);
FORCEPROP 1 LAST SIZE 1B
J 0
(-1300 4475);
DISPLAY 0.872340 (-1300 4475);
PAINT GREEN (-1300 4475);
DISPLAY INVISIBLE (-1300 4475);
FORCEPROP 2 LAST CDS_LIB pure_quanta_power
J 0
(-1375 4525);
DISPLAY INVISIBLE (-1375 4525);
FORCEPROP 1 LAST HDL_POWER GND
J 0
(-1375 4675);
DISPLAY 0.872340 (-1375 4675);
PAINT GREEN (-1375 4675);
DISPLAY INVISIBLE (-1375 4675);
FORCEPROP 1 LAST PATH I57
J 0
(-1300 4525);
DISPLAY 0.872340 (-1300 4525);
PAINT AQUA (-1300 4525);
DISPLAY INVISIBLE (-1300 4525);
FORCEADD Q_CAP..1
R 2
(-725 5250);
FORCEPROP 1 LAST LOCATION C6064
J 2
(-775 5350);
DISPLAY 0.978723 (-775 5350);
FORCEPROP 0 LAST $SEC 1
J 0
(-775 5400);
DISPLAY 0.680851 (-775 5400);
PAINT MONO (-775 5400);
DISPLAY INVISIBLE (-775 5400);
FORCEPROP 0 LAST CDS_SEC 1
J 0
(-775 5400);
DISPLAY 0.680851 (-775 5400);
DISPLAY INVISIBLE (-775 5400);
FORCEPROP 1 LASTPIN (-725 5350) $PN 1
J 2
(-735 5330);
DISPLAY 0.787234 (-735 5330);
PAINT MONO (-735 5330);
FORCEPROP 1 LASTPIN (-725 5150) $PN 2
J 2
(-735 5130);
DISPLAY 0.787234 (-735 5130);
PAINT MONO (-735 5130);
FORCEPROP 2 LAST ROOM USB3_HUB1_CYP
J 0
(-1075 5125);
DISPLAY 0.446809 (-1075 5125);
PAINT RED (-1075 5125);
FORCEPROP 1 LAST VOLTAGE 25V
J 2
(-775 5250);
DISPLAY 0.978723 (-775 5250);
FORCEPROP 1 LAST TOLERANCE 10%
J 2
(-775 5200);
DISPLAY 0.978723 (-775 5200);
FORCEPROP 1 LAST MATERIAL X7R
J 2
(-775 5150);
DISPLAY 0.978723 (-775 5150);
FORCEPROP 1 LAST PACK_TYPE 0402
J 2
(-775 5050);
DISPLAY 0.978723 (-775 5050);
FORCEPROP 1 LAST VALUE 0.1UF
J 2
(-775 5300);
DISPLAY 0.978723 (-775 5300);
FORCEPROP 2 LAST CDS_LIB pure_quanta
J 2
(-725 5250);
DISPLAY INVISIBLE (-725 5250);
FORCEPROP 1 LAST PATH I58
J 2
(-775 5400);
DISPLAY 0.978723 (-775 5400);
PAINT WHITE (-775 5400);
DISPLAY INVISIBLE (-775 5400);
FORCEPROP 1 LAST PART_NUMBER CH4104K1B00
J 2
(-775 5100);
DISPLAY 0.808511 (-775 5100);
DISPLAY INVISIBLE (-775 5100);
FORCEADD Q_CAP..1
(-600 5250);
FORCEPROP 1 LAST LOCATION C6065
J 0
(-550 5350);
DISPLAY 0.978723 (-550 5350);
FORCEPROP 0 LAST $SEC 1
J 0
(-550 5400);
DISPLAY 0.680851 (-550 5400);
PAINT MONO (-550 5400);
DISPLAY INVISIBLE (-550 5400);
FORCEPROP 0 LAST CDS_SEC 1
J 0
(-550 5400);
DISPLAY 0.680851 (-550 5400);
DISPLAY INVISIBLE (-550 5400);
FORCEPROP 1 LASTPIN (-600 5350) $PN 1
J 0
(-590 5330);
DISPLAY 0.787234 (-590 5330);
PAINT MONO (-590 5330);
FORCEPROP 1 LASTPIN (-600 5150) $PN 2
J 0
(-590 5130);
DISPLAY 0.787234 (-590 5130);
PAINT MONO (-590 5130);
FORCEPROP 1 LAST PACK_TYPE C0402
J 0
(-550 5050);
DISPLAY 0.978723 (-550 5050);
FORCEPROP 2 LAST ROOM USB3_HUB1_CYP
J 0
(-575 5000);
DISPLAY 0.361702 (-575 5000);
PAINT RED (-575 5000);
FORCEPROP 1 LAST VALUE 1UF
J 0
(-550 5300);
DISPLAY 0.978723 (-550 5300);
FORCEPROP 1 LAST MATERIAL X6S
J 0
(-550 5150);
DISPLAY 0.978723 (-550 5150);
FORCEPROP 1 LAST VOLTAGE 25V
J 0
(-550 5250);
DISPLAY 0.978723 (-550 5250);
FORCEPROP 1 LAST TOLERANCE 10%
J 0
(-550 5200);
DISPLAY 0.978723 (-550 5200);
FORCEPROP 2 LAST CDS_LIB pure_quanta
J 0
(-600 5250);
DISPLAY INVISIBLE (-600 5250);
FORCEPROP 1 LAST PATH I59
J 0
(-550 5400);
DISPLAY 0.978723 (-550 5400);
PAINT WHITE (-550 5400);
DISPLAY INVISIBLE (-550 5400);
FORCEPROP 1 LAST PART_NUMBER CH5104KEB02
J 0
(-550 5100);
DISPLAY 0.787234 (-550 5100);
DISPLAY INVISIBLE (-550 5100);
FORCEADD Q_CAP..1
(-325 5250);
FORCEPROP 1 LAST LOCATION C6066
J 0
(-275 5350);
DISPLAY 0.978723 (-275 5350);
FORCEPROP 0 LAST $SEC 1
J 0
(-275 5400);
DISPLAY 0.680851 (-275 5400);
PAINT MONO (-275 5400);
DISPLAY INVISIBLE (-275 5400);
FORCEPROP 0 LAST CDS_SEC 1
J 0
(-275 5400);
DISPLAY 0.680851 (-275 5400);
DISPLAY INVISIBLE (-275 5400);
FORCEPROP 1 LASTPIN (-325 5350) $PN 1
J 0
(-315 5330);
DISPLAY 0.787234 (-315 5330);
PAINT MONO (-315 5330);
FORCEPROP 1 LASTPIN (-325 5150) $PN 2
J 0
(-315 5130);
DISPLAY 0.787234 (-315 5130);
PAINT MONO (-315 5130);
FORCEPROP 2 LAST ROOM USB3_HUB1_CYP
J 0
(-275 5125);
DISPLAY 0.361702 (-275 5125);
PAINT RED (-275 5125);
FORCEPROP 1 LAST PACK_TYPE C0603
J 0
(-275 5050);
DISPLAY 0.978723 (-275 5050);
FORCEPROP 1 LAST MATERIAL X6S
J 0
(-275 5150);
DISPLAY 0.978723 (-275 5150);
FORCEPROP 1 LAST TOLERANCE 20%
J 0
(-275 5200);
DISPLAY 0.978723 (-275 5200);
FORCEPROP 1 LAST VOLTAGE 6.3V
J 0
(-275 5250);
DISPLAY 0.978723 (-275 5250);
FORCEPROP 1 LAST VALUE 22UF
J 0
(-275 5300);
DISPLAY 0.978723 (-275 5300);
FORCEPROP 2 LAST CDS_LIB pure_quanta
J 0
(-325 5250);
DISPLAY INVISIBLE (-325 5250);
FORCEPROP 1 LAST PATH I60
J 0
(-275 5400);
DISPLAY 0.978723 (-275 5400);
PAINT WHITE (-275 5400);
DISPLAY INVISIBLE (-275 5400);
FORCEPROP 1 LAST PART_NUMBER CH6221ME900
J 0
(-275 5100);
DISPLAY 0.787234 (-275 5100);
DISPLAY INVISIBLE (-275 5100);
FORCEADD GND..1
(-325 4825);
FORCEPROP 3 LASTPIN (-325 4875) SIG_NAME GND\g
J 0
(-315 4885);
DISPLAY 0.659574 (-315 4885);
PAINT MONO (-315 4885);
DISPLAY INVISIBLE (-315 4885);
FORCEPROP 1 LAST SIZE 1B
J 0
(-250 4775);
DISPLAY 0.872340 (-250 4775);
PAINT GREEN (-250 4775);
DISPLAY INVISIBLE (-250 4775);
FORCEPROP 2 LAST CDS_LIB pure_quanta_power
J 0
(-325 4825);
DISPLAY INVISIBLE (-325 4825);
FORCEPROP 1 LAST HDL_POWER GND
J 0
(-325 4975);
DISPLAY 0.872340 (-325 4975);
PAINT GREEN (-325 4975);
DISPLAY INVISIBLE (-325 4975);
FORCEPROP 1 LAST PATH I61
J 0
(-250 4825);
DISPLAY 0.872340 (-250 4825);
PAINT AQUA (-250 4825);
DISPLAY INVISIBLE (-250 4825);
FORCEADD GND..1
(-3200 3025);
FORCEPROP 3 LASTPIN (-3200 3075) SIG_NAME GND\g
J 0
(-3190 3085);
DISPLAY 0.659574 (-3190 3085);
PAINT MONO (-3190 3085);
DISPLAY INVISIBLE (-3190 3085);
FORCEPROP 2 LAST CDS_LIB pure_quanta_power
J 0
(-3200 3025);
DISPLAY INVISIBLE (-3200 3025);
FORCEPROP 1 LAST SIZE 1B
J 0
(-3125 2975);
DISPLAY 0.872340 (-3125 2975);
PAINT GREEN (-3125 2975);
DISPLAY INVISIBLE (-3125 2975);
FORCEPROP 1 LAST HDL_POWER GND
J 0
(-3200 3175);
DISPLAY 0.872340 (-3200 3175);
PAINT GREEN (-3200 3175);
DISPLAY INVISIBLE (-3200 3175);
FORCEPROP 1 LAST PATH I62
J 0
(-3125 3025);
DISPLAY 0.872340 (-3125 3025);
PAINT AQUA (-3125 3025);
DISPLAY INVISIBLE (-3125 3025);
FORCEADD Q_CAP..1
(-3250 3350);
FORCEPROP 1 LAST LOCATION C6069
J 0
(-3200 3450);
DISPLAY 0.617021 (-3200 3450);
PAINT SKYBLUE (-3200 3450);
FORCEPROP 0 LAST $SEC 1
J 0
(-3200 3500);
DISPLAY 0.680851 (-3200 3500);
PAINT MONO (-3200 3500);
DISPLAY INVISIBLE (-3200 3500);
FORCEPROP 0 LAST CDS_SEC 1
J 0
(-3200 3500);
DISPLAY 0.680851 (-3200 3500);
DISPLAY INVISIBLE (-3200 3500);
FORCEPROP 1 LASTPIN (-3250 3450) $PN 1
J 0
(-3240 3430);
DISPLAY 0.787234 (-3240 3430);
PAINT MONO (-3240 3430);
FORCEPROP 1 LASTPIN (-3250 3250) $PN 2
J 0
(-3240 3230);
DISPLAY 0.787234 (-3240 3230);
PAINT MONO (-3240 3230);
FORCEPROP 1 LAST VOLTAGE 50V
J 0
(-3200 3350);
DISPLAY 0.489362 (-3200 3350);
PAINT SKYBLUE (-3200 3350);
FORCEPROP 1 LAST MATERIAL X7R
J 0
(-3200 3250);
DISPLAY 0.489362 (-3200 3250);
PAINT SKYBLUE (-3200 3250);
FORCEPROP 1 LAST PACK_TYPE C0402
J 0
(-3200 3200);
DISPLAY 0.489362 (-3200 3200);
PAINT SKYBLUE (-3200 3200);
FORCEPROP 1 LAST TOLERANCE 10%
J 0
(-3200 3300);
DISPLAY 0.489362 (-3200 3300);
PAINT SKYBLUE (-3200 3300);
FORCEPROP 1 LAST VALUE 0.001UF
J 0
(-3200 3400);
DISPLAY 0.489362 (-3200 3400);
PAINT SKYBLUE (-3200 3400);
FORCEPROP 2 LAST ROOM USB3_HUB1_CYP
J 0
(-3200 3150);
DISPLAY 0.297872 (-3200 3150);
PAINT RED (-3200 3150);
FORCEPROP 2 LAST CDS_LIB pure_quanta
J 0
(-3250 3350);
DISPLAY INVISIBLE (-3250 3350);
FORCEPROP 1 LAST PATH I63
J 0
(-3200 3500);
DISPLAY 0.978723 (-3200 3500);
PAINT WHITE (-3200 3500);
DISPLAY INVISIBLE (-3200 3500);
FORCEPROP 1 LAST PART_NUMBER CH30106KB19
J 0
(-3200 3250);
DISPLAY 0.808511 (-3200 3250);
PAINT SKYBLUE (-3200 3250);
DISPLAY INVISIBLE (-3200 3250);
FORCEADD Q_CAP..1
(-325 3750);
FORCEPROP 1 LAST LOCATION C6079
J 0
(-275 3850);
DISPLAY 0.978723 (-275 3850);
FORCEPROP 0 LAST $SEC 1
J 0
(-275 3900);
DISPLAY 0.680851 (-275 3900);
PAINT MONO (-275 3900);
DISPLAY INVISIBLE (-275 3900);
FORCEPROP 0 LAST CDS_SEC 1
J 0
(-275 3900);
DISPLAY 0.680851 (-275 3900);
DISPLAY INVISIBLE (-275 3900);
FORCEPROP 1 LASTPIN (-325 3850) $PN 1
J 0
(-315 3830);
DISPLAY 0.787234 (-315 3830);
PAINT MONO (-315 3830);
FORCEPROP 1 LASTPIN (-325 3650) $PN 2
J 0
(-315 3630);
DISPLAY 0.787234 (-315 3630);
PAINT MONO (-315 3630);
FORCEPROP 2 LAST ROOM USB3_HUB1_CYP
J 0
(-275 3600);
DISPLAY 0.361702 (-275 3600);
PAINT RED (-275 3600);
FORCEPROP 1 LAST PACK_TYPE C0603
J 0
(-275 3550);
DISPLAY 0.978723 (-275 3550);
FORCEPROP 1 LAST VALUE 22UF
J 0
(-275 3800);
DISPLAY 0.978723 (-275 3800);
FORCEPROP 1 LAST VOLTAGE 6.3V
J 0
(-275 3750);
DISPLAY 0.978723 (-275 3750);
FORCEPROP 1 LAST TOLERANCE 20%
J 0
(-275 3700);
DISPLAY 0.978723 (-275 3700);
FORCEPROP 1 LAST MATERIAL X6S
J 0
(-275 3650);
DISPLAY 0.978723 (-275 3650);
FORCEPROP 2 LAST CDS_LIB pure_quanta
J 0
(-325 3750);
DISPLAY INVISIBLE (-325 3750);
FORCEPROP 1 LAST PATH I64
J 0
(-275 3900);
DISPLAY 0.978723 (-275 3900);
PAINT WHITE (-275 3900);
DISPLAY INVISIBLE (-275 3900);
FORCEPROP 1 LAST PART_NUMBER CH6221ME900
J 0
(-275 3600);
DISPLAY 0.787234 (-275 3600);
DISPLAY INVISIBLE (-275 3600);
FORCEADD Q_CAP..1
(-600 3750);
FORCEPROP 1 LAST LOCATION C6078
J 0
(-550 3850);
DISPLAY 0.978723 (-550 3850);
FORCEPROP 0 LAST $SEC 1
J 0
(-550 3900);
DISPLAY 0.680851 (-550 3900);
PAINT MONO (-550 3900);
DISPLAY INVISIBLE (-550 3900);
FORCEPROP 0 LAST CDS_SEC 1
J 0
(-550 3900);
DISPLAY 0.680851 (-550 3900);
DISPLAY INVISIBLE (-550 3900);
FORCEPROP 1 LASTPIN (-600 3850) $PN 1
J 0
(-590 3830);
DISPLAY 0.787234 (-590 3830);
PAINT MONO (-590 3830);
FORCEPROP 1 LASTPIN (-600 3650) $PN 2
J 0
(-590 3630);
DISPLAY 0.787234 (-590 3630);
PAINT MONO (-590 3630);
FORCEPROP 2 LAST ROOM USB3_HUB1_CYP
J 0
(-575 3525);
DISPLAY 0.361702 (-575 3525);
PAINT RED (-575 3525);
FORCEPROP 1 LAST PACK_TYPE C0402
J 0
(-550 3550);
DISPLAY 0.978723 (-550 3550);
FORCEPROP 1 LAST MATERIAL X6S
J 0
(-550 3650);
DISPLAY 0.978723 (-550 3650);
FORCEPROP 1 LAST VALUE 1UF
J 0
(-550 3800);
DISPLAY 0.978723 (-550 3800);
FORCEPROP 1 LAST TOLERANCE 10%
J 0
(-550 3700);
DISPLAY 0.978723 (-550 3700);
FORCEPROP 1 LAST VOLTAGE 25V
J 0
(-550 3750);
DISPLAY 0.978723 (-550 3750);
FORCEPROP 2 LAST CDS_LIB pure_quanta
J 0
(-600 3750);
DISPLAY INVISIBLE (-600 3750);
FORCEPROP 1 LAST PATH I65
J 0
(-550 3900);
DISPLAY 0.978723 (-550 3900);
PAINT WHITE (-550 3900);
DISPLAY INVISIBLE (-550 3900);
FORCEPROP 1 LAST PART_NUMBER CH5104KEB02
J 0
(-550 3600);
DISPLAY 0.787234 (-550 3600);
DISPLAY INVISIBLE (-550 3600);
FORCEADD Q_CAP..1
R 2
(-725 3750);
FORCEPROP 1 LAST LOCATION C6077
J 2
(-775 3850);
DISPLAY 0.978723 (-775 3850);
FORCEPROP 0 LAST $SEC 1
J 0
(-775 3900);
DISPLAY 0.680851 (-775 3900);
PAINT MONO (-775 3900);
DISPLAY INVISIBLE (-775 3900);
FORCEPROP 0 LAST CDS_SEC 1
J 0
(-775 3900);
DISPLAY 0.680851 (-775 3900);
DISPLAY INVISIBLE (-775 3900);
FORCEPROP 1 LASTPIN (-725 3850) $PN 1
J 2
(-735 3830);
DISPLAY 0.787234 (-735 3830);
PAINT MONO (-735 3830);
FORCEPROP 1 LASTPIN (-725 3650) $PN 2
J 2
(-735 3630);
DISPLAY 0.787234 (-735 3630);
PAINT MONO (-735 3630);
FORCEPROP 2 LAST ROOM USB3_HUB1_CYP
J 0
(-1050 3600);
DISPLAY 0.446809 (-1050 3600);
PAINT RED (-1050 3600);
FORCEPROP 1 LAST TOLERANCE 10%
J 2
(-775 3700);
DISPLAY 0.978723 (-775 3700);
FORCEPROP 1 LAST VOLTAGE 25V
J 2
(-775 3750);
DISPLAY 0.978723 (-775 3750);
FORCEPROP 1 LAST MATERIAL X7R
J 2
(-775 3650);
DISPLAY 0.978723 (-775 3650);
FORCEPROP 1 LAST VALUE 0.1UF
J 2
(-775 3800);
DISPLAY 0.978723 (-775 3800);
FORCEPROP 1 LAST PACK_TYPE 0402
J 2
(-775 3550);
DISPLAY 0.978723 (-775 3550);
FORCEPROP 2 LAST CDS_LIB pure_quanta
J 0
(-725 3750);
DISPLAY INVISIBLE (-725 3750);
FORCEPROP 1 LAST PATH I66
J 2
(-775 3900);
DISPLAY 0.978723 (-775 3900);
PAINT WHITE (-775 3900);
DISPLAY INVISIBLE (-775 3900);
FORCEPROP 1 LAST PART_NUMBER CH4104K1B00
J 2
(-775 3600);
DISPLAY 0.808511 (-775 3600);
DISPLAY INVISIBLE (-775 3600);
FORCEADD GND..1
(-325 3325);
FORCEPROP 3 LASTPIN (-325 3375) SIG_NAME GND\g
J 0
(-315 3385);
DISPLAY 0.659574 (-315 3385);
PAINT MONO (-315 3385);
DISPLAY INVISIBLE (-315 3385);
FORCEPROP 2 LAST CDS_LIB pure_quanta_power
J 0
(-325 3325);
DISPLAY INVISIBLE (-325 3325);
FORCEPROP 1 LAST SIZE 1B
J 0
(-250 3275);
DISPLAY 0.872340 (-250 3275);
PAINT GREEN (-250 3275);
DISPLAY INVISIBLE (-250 3275);
FORCEPROP 1 LAST HDL_POWER GND
J 0
(-325 3475);
DISPLAY 0.872340 (-325 3475);
PAINT GREEN (-325 3475);
DISPLAY INVISIBLE (-325 3475);
FORCEPROP 1 LAST PATH I67
J 0
(-250 3325);
DISPLAY 0.872340 (-250 3325);
PAINT AQUA (-250 3325);
DISPLAY INVISIBLE (-250 3325);
FORCEADD Q_CAP..1
(-1175 3350);
FORCEPROP 1 LAST LOCATION C6076
J 0
(-1125 3450);
DISPLAY 0.978723 (-1125 3450);
FORCEPROP 0 LAST $SEC 1
J 0
(-1125 3500);
DISPLAY 0.680851 (-1125 3500);
PAINT MONO (-1125 3500);
DISPLAY INVISIBLE (-1125 3500);
FORCEPROP 0 LAST CDS_SEC 1
J 0
(-1125 3500);
DISPLAY 0.680851 (-1125 3500);
DISPLAY INVISIBLE (-1125 3500);
FORCEPROP 1 LASTPIN (-1175 3450) $PN 1
J 0
(-1165 3430);
DISPLAY 0.787234 (-1165 3430);
PAINT MONO (-1165 3430);
FORCEPROP 1 LASTPIN (-1175 3250) $PN 2
J 0
(-1165 3230);
DISPLAY 0.787234 (-1165 3230);
PAINT MONO (-1165 3230);
FORCEPROP 2 LAST ROOM USB3_HUB1_CYP
J 0
(-1125 3200);
DISPLAY 0.553191 (-1125 3200);
PAINT RED (-1125 3200);
FORCEPROP 1 LAST VALUE 0.01UF
J 0
(-1125 3400);
DISPLAY 0.510638 (-1125 3400);
FORCEPROP 1 LAST MATERIAL X7R
J 0
(-1125 3250);
DISPLAY 0.510638 (-1125 3250);
FORCEPROP 1 LAST TOLERANCE 10%
J 0
(-1125 3300);
DISPLAY 0.510638 (-1125 3300);
FORCEPROP 1 LAST VOLTAGE 50V
J 0
(-1125 3350);
DISPLAY 0.510638 (-1125 3350);
FORCEPROP 1 LAST PACK_TYPE C0402
J 0
(-1125 3150);
DISPLAY 0.510638 (-1125 3150);
FORCEPROP 2 LAST CDS_LIB pure_quanta
J 0
(-1175 3350);
DISPLAY INVISIBLE (-1175 3350);
FORCEPROP 1 LAST PATH I68
J 0
(-1125 3500);
DISPLAY 0.978723 (-1125 3500);
PAINT WHITE (-1125 3500);
DISPLAY INVISIBLE (-1125 3500);
FORCEPROP 1 LAST PART_NUMBER CH31006KB18
J 0
(-1125 3200);
DISPLAY 0.638298 (-1125 3200);
DISPLAY INVISIBLE (-1125 3200);
FORCEADD Q_CAP..1
(-1425 3350);
FORCEPROP 1 LAST LOCATION C6075
J 0
(-1375 3450);
DISPLAY 0.617021 (-1375 3450);
PAINT SKYBLUE (-1375 3450);
FORCEPROP 0 LAST $SEC 1
J 0
(-1375 3500);
DISPLAY 0.680851 (-1375 3500);
PAINT MONO (-1375 3500);
DISPLAY INVISIBLE (-1375 3500);
FORCEPROP 0 LAST CDS_SEC 1
J 0
(-1375 3500);
DISPLAY 0.680851 (-1375 3500);
DISPLAY INVISIBLE (-1375 3500);
FORCEPROP 1 LASTPIN (-1425 3450) $PN 1
J 0
(-1415 3430);
DISPLAY 0.787234 (-1415 3430);
PAINT MONO (-1415 3430);
FORCEPROP 1 LASTPIN (-1425 3250) $PN 2
J 0
(-1415 3230);
DISPLAY 0.787234 (-1415 3230);
PAINT MONO (-1415 3230);
FORCEPROP 2 LAST ROOM USB3_HUB1_CYP
J 0
(-1400 3150);
DISPLAY 0.361702 (-1400 3150);
PAINT RED (-1400 3150);
FORCEPROP 1 LAST PACK_TYPE C0402
J 0
(-1375 3200);
DISPLAY 0.489362 (-1375 3200);
PAINT SKYBLUE (-1375 3200);
FORCEPROP 1 LAST VALUE 0.001UF
J 0
(-1375 3400);
DISPLAY 0.489362 (-1375 3400);
PAINT SKYBLUE (-1375 3400);
FORCEPROP 1 LAST TOLERANCE 10%
J 0
(-1375 3300);
DISPLAY 0.489362 (-1375 3300);
PAINT SKYBLUE (-1375 3300);
FORCEPROP 1 LAST MATERIAL X7R
J 0
(-1375 3250);
DISPLAY 0.489362 (-1375 3250);
PAINT SKYBLUE (-1375 3250);
FORCEPROP 1 LAST VOLTAGE 50V
J 0
(-1375 3350);
DISPLAY 0.489362 (-1375 3350);
PAINT SKYBLUE (-1375 3350);
FORCEPROP 2 LAST CDS_LIB pure_quanta
J 0
(-1425 3350);
DISPLAY INVISIBLE (-1425 3350);
FORCEPROP 1 LAST PATH I69
J 0
(-1375 3500);
DISPLAY 0.978723 (-1375 3500);
PAINT WHITE (-1375 3500);
DISPLAY INVISIBLE (-1375 3500);
FORCEPROP 1 LAST PART_NUMBER CH30106KB19
J 0
(-1375 3250);
DISPLAY 0.808511 (-1375 3250);
PAINT SKYBLUE (-1375 3250);
DISPLAY INVISIBLE (-1375 3250);
FORCEADD Q_CAP..1
(-6425 3900);
FORCEPROP 1 LAST LOCATION C6041
J 0
(-6375 4000);
DISPLAY 0.978723 (-6375 4000);
FORCEPROP 0 LAST $SEC 1
J 0
(-6375 4050);
DISPLAY 0.680851 (-6375 4050);
PAINT MONO (-6375 4050);
DISPLAY INVISIBLE (-6375 4050);
FORCEPROP 0 LAST CDS_SEC 1
J 0
(-6375 4050);
DISPLAY 0.680851 (-6375 4050);
DISPLAY INVISIBLE (-6375 4050);
FORCEPROP 1 LASTPIN (-6425 4000) $PN 1
J 0
(-6415 3980);
DISPLAY 0.787234 (-6415 3980);
PAINT MONO (-6415 3980);
FORCEPROP 1 LASTPIN (-6425 3800) $PN 2
J 0
(-6415 3780);
DISPLAY 0.787234 (-6415 3780);
PAINT MONO (-6415 3780);
FORCEPROP 1 LAST PACK_TYPE 0402
J 0
(-6375 3700);
DISPLAY 0.978723 (-6375 3700);
FORCEPROP 1 LAST MATERIAL X7R
J 0
(-6375 3800);
DISPLAY 0.978723 (-6375 3800);
FORCEPROP 1 LAST TOLERANCE 10%
J 0
(-6375 3850);
DISPLAY 0.978723 (-6375 3850);
FORCEPROP 1 LAST VALUE 0.1UF
J 0
(-6375 3950);
DISPLAY 0.978723 (-6375 3950);
FORCEPROP 1 LAST VOLTAGE 25V
J 0
(-6375 3900);
DISPLAY 0.978723 (-6375 3900);
FORCEPROP 2 LAST ROOM USB3_HUB1_CYP
J 0
(-6375 4050);
DISPLAY 0.553191 (-6375 4050);
PAINT RED (-6375 4050);
FORCEPROP 2 LAST CDS_LIB pure_quanta
J 0
(-6425 3900);
DISPLAY INVISIBLE (-6425 3900);
FORCEPROP 1 LAST PATH I7
J 0
(-6375 4050);
DISPLAY 0.978723 (-6375 4050);
PAINT WHITE (-6375 4050);
DISPLAY INVISIBLE (-6375 4050);
FORCEPROP 1 LAST PART_NUMBER CH4104K1B00
J 0
(-6375 3750);
DISPLAY 0.808511 (-6375 3750);
DISPLAY INVISIBLE (-6375 3750);
FORCEADD GND..1
(-1375 3025);
FORCEPROP 3 LASTPIN (-1375 3075) SIG_NAME GND\g
J 0
(-1365 3085);
DISPLAY 0.659574 (-1365 3085);
PAINT MONO (-1365 3085);
DISPLAY INVISIBLE (-1365 3085);
FORCEPROP 2 LAST CDS_LIB pure_quanta_power
J 0
(-1375 3025);
DISPLAY INVISIBLE (-1375 3025);
FORCEPROP 1 LAST SIZE 1B
J 0
(-1300 2975);
DISPLAY 0.872340 (-1300 2975);
PAINT GREEN (-1300 2975);
DISPLAY INVISIBLE (-1300 2975);
FORCEPROP 1 LAST HDL_POWER GND
J 0
(-1375 3175);
DISPLAY 0.872340 (-1375 3175);
PAINT GREEN (-1375 3175);
DISPLAY INVISIBLE (-1375 3175);
FORCEPROP 1 LAST PATH I70
J 0
(-1300 3025);
DISPLAY 0.872340 (-1300 3025);
PAINT AQUA (-1300 3025);
DISPLAY INVISIBLE (-1300 3025);
FORCEADD Q_CAP..1
(-1775 3350);
FORCEPROP 1 LAST LOCATION C6074
J 0
(-1725 3450);
DISPLAY 0.978723 (-1725 3450);
FORCEPROP 0 LAST $SEC 1
J 0
(-1725 3500);
DISPLAY 0.680851 (-1725 3500);
PAINT MONO (-1725 3500);
DISPLAY INVISIBLE (-1725 3500);
FORCEPROP 0 LAST CDS_SEC 1
J 0
(-1725 3500);
DISPLAY 0.680851 (-1725 3500);
DISPLAY INVISIBLE (-1725 3500);
FORCEPROP 1 LASTPIN (-1775 3450) $PN 1
J 0
(-1765 3430);
DISPLAY 0.787234 (-1765 3430);
PAINT MONO (-1765 3430);
FORCEPROP 1 LASTPIN (-1775 3250) $PN 2
J 0
(-1765 3230);
DISPLAY 0.787234 (-1765 3230);
PAINT MONO (-1765 3230);
FORCEPROP 1 LAST PACK_TYPE C0402
J 0
(-1725 3150);
DISPLAY 0.510638 (-1725 3150);
FORCEPROP 2 LAST ROOM USB3_HUB1_CYP
J 0
(-1725 3200);
DISPLAY 0.446809 (-1725 3200);
PAINT RED (-1725 3200);
FORCEPROP 1 LAST TOLERANCE 10%
J 0
(-1725 3300);
DISPLAY 0.510638 (-1725 3300);
FORCEPROP 1 LAST MATERIAL X7R
J 0
(-1725 3250);
DISPLAY 0.510638 (-1725 3250);
FORCEPROP 1 LAST VOLTAGE 50V
J 0
(-1725 3350);
DISPLAY 0.510638 (-1725 3350);
FORCEPROP 1 LAST VALUE 0.01UF
J 0
(-1725 3400);
DISPLAY 0.510638 (-1725 3400);
FORCEPROP 2 LAST CDS_LIB pure_quanta
J 0
(-1775 3350);
DISPLAY INVISIBLE (-1775 3350);
FORCEPROP 1 LAST PATH I71
J 0
(-1725 3500);
DISPLAY 0.978723 (-1725 3500);
PAINT WHITE (-1725 3500);
DISPLAY INVISIBLE (-1725 3500);
FORCEPROP 1 LAST PART_NUMBER CH31006KB18
J 0
(-1725 3200);
DISPLAY 0.638298 (-1725 3200);
DISPLAY INVISIBLE (-1725 3200);
FORCEADD GND..1
(-1975 3025);
FORCEPROP 3 LASTPIN (-1975 3075) SIG_NAME GND\g
J 0
(-1965 3085);
DISPLAY 0.659574 (-1965 3085);
PAINT MONO (-1965 3085);
DISPLAY INVISIBLE (-1965 3085);
FORCEPROP 2 LAST CDS_LIB pure_quanta_power
J 0
(-1975 3025);
DISPLAY INVISIBLE (-1975 3025);
FORCEPROP 1 LAST SIZE 1B
J 0
(-1900 2975);
DISPLAY 0.872340 (-1900 2975);
PAINT GREEN (-1900 2975);
DISPLAY INVISIBLE (-1900 2975);
FORCEPROP 1 LAST HDL_POWER GND
J 0
(-1975 3175);
DISPLAY 0.872340 (-1975 3175);
PAINT GREEN (-1975 3175);
DISPLAY INVISIBLE (-1975 3175);
FORCEPROP 1 LAST PATH I72
J 0
(-1900 3025);
DISPLAY 0.872340 (-1900 3025);
PAINT AQUA (-1900 3025);
DISPLAY INVISIBLE (-1900 3025);
FORCEADD Q_CAP..1
(-2025 3350);
FORCEPROP 1 LAST LOCATION C6073
J 0
(-1975 3450);
DISPLAY 0.617021 (-1975 3450);
PAINT SKYBLUE (-1975 3450);
FORCEPROP 0 LAST $SEC 1
J 0
(-1975 3500);
DISPLAY 0.680851 (-1975 3500);
PAINT MONO (-1975 3500);
DISPLAY INVISIBLE (-1975 3500);
FORCEPROP 0 LAST CDS_SEC 1
J 0
(-1975 3500);
DISPLAY 0.680851 (-1975 3500);
DISPLAY INVISIBLE (-1975 3500);
FORCEPROP 1 LASTPIN (-2025 3450) $PN 1
J 0
(-2015 3430);
DISPLAY 0.787234 (-2015 3430);
PAINT MONO (-2015 3430);
FORCEPROP 1 LASTPIN (-2025 3250) $PN 2
J 0
(-2015 3230);
DISPLAY 0.787234 (-2015 3230);
PAINT MONO (-2015 3230);
FORCEPROP 2 LAST ROOM USB3_HUB1_CYP
J 0
(-2000 3150);
DISPLAY 0.361702 (-2000 3150);
PAINT RED (-2000 3150);
FORCEPROP 1 LAST VALUE 0.001UF
J 0
(-1975 3400);
DISPLAY 0.489362 (-1975 3400);
PAINT SKYBLUE (-1975 3400);
FORCEPROP 1 LAST MATERIAL X7R
J 0
(-1975 3250);
DISPLAY 0.489362 (-1975 3250);
PAINT SKYBLUE (-1975 3250);
FORCEPROP 1 LAST TOLERANCE 10%
J 0
(-1975 3300);
DISPLAY 0.489362 (-1975 3300);
PAINT SKYBLUE (-1975 3300);
FORCEPROP 1 LAST VOLTAGE 50V
J 0
(-1975 3350);
DISPLAY 0.489362 (-1975 3350);
PAINT SKYBLUE (-1975 3350);
FORCEPROP 1 LAST PACK_TYPE C0402
J 0
(-1975 3200);
DISPLAY 0.489362 (-1975 3200);
PAINT SKYBLUE (-1975 3200);
FORCEPROP 2 LAST CDS_LIB pure_quanta
J 0
(-2025 3350);
DISPLAY INVISIBLE (-2025 3350);
FORCEPROP 1 LAST PATH I73
J 0
(-1975 3500);
DISPLAY 0.978723 (-1975 3500);
PAINT WHITE (-1975 3500);
DISPLAY INVISIBLE (-1975 3500);
FORCEPROP 1 LAST PART_NUMBER CH30106KB19
J 0
(-1975 3250);
DISPLAY 0.808511 (-1975 3250);
PAINT SKYBLUE (-1975 3250);
DISPLAY INVISIBLE (-1975 3250);
FORCEADD Q_CAP..1
(-2400 3350);
FORCEPROP 1 LAST LOCATION C6072
J 0
(-2350 3450);
DISPLAY 0.978723 (-2350 3450);
FORCEPROP 0 LAST $SEC 1
J 0
(-2350 3500);
DISPLAY 0.680851 (-2350 3500);
PAINT MONO (-2350 3500);
DISPLAY INVISIBLE (-2350 3500);
FORCEPROP 0 LAST CDS_SEC 1
J 0
(-2350 3500);
DISPLAY 0.680851 (-2350 3500);
DISPLAY INVISIBLE (-2350 3500);
FORCEPROP 1 LASTPIN (-2400 3450) $PN 1
J 0
(-2390 3430);
DISPLAY 0.787234 (-2390 3430);
PAINT MONO (-2390 3430);
FORCEPROP 1 LASTPIN (-2400 3250) $PN 2
J 0
(-2390 3230);
DISPLAY 0.787234 (-2390 3230);
PAINT MONO (-2390 3230);
FORCEPROP 1 LAST TOLERANCE 10%
J 0
(-2350 3300);
DISPLAY 0.510638 (-2350 3300);
FORCEPROP 1 LAST PACK_TYPE C0402
J 0
(-2350 3150);
DISPLAY 0.510638 (-2350 3150);
FORCEPROP 1 LAST MATERIAL X7R
J 0
(-2350 3250);
DISPLAY 0.510638 (-2350 3250);
FORCEPROP 1 LAST VOLTAGE 50V
J 0
(-2350 3350);
DISPLAY 0.510638 (-2350 3350);
FORCEPROP 1 LAST VALUE 0.01UF
J 0
(-2350 3400);
DISPLAY 0.510638 (-2350 3400);
FORCEPROP 2 LAST ROOM USB3_HUB1_CYP
J 0
(-2350 3200);
DISPLAY 0.446809 (-2350 3200);
PAINT RED (-2350 3200);
FORCEPROP 2 LAST CDS_LIB pure_quanta
J 0
(-2400 3350);
DISPLAY INVISIBLE (-2400 3350);
FORCEPROP 1 LAST PATH I74
J 0
(-2350 3500);
DISPLAY 0.978723 (-2350 3500);
PAINT WHITE (-2350 3500);
DISPLAY INVISIBLE (-2350 3500);
FORCEPROP 1 LAST PART_NUMBER CH31006KB18
J 0
(-2350 3200);
DISPLAY 0.638298 (-2350 3200);
DISPLAY INVISIBLE (-2350 3200);
FORCEADD Q_CAP..1
(-2650 3350);
FORCEPROP 1 LAST LOCATION C6071
J 0
(-2600 3450);
DISPLAY 0.617021 (-2600 3450);
PAINT SKYBLUE (-2600 3450);
FORCEPROP 0 LAST $SEC 1
J 0
(-2600 3500);
DISPLAY 0.680851 (-2600 3500);
PAINT MONO (-2600 3500);
DISPLAY INVISIBLE (-2600 3500);
FORCEPROP 0 LAST CDS_SEC 1
J 0
(-2600 3500);
DISPLAY 0.680851 (-2600 3500);
DISPLAY INVISIBLE (-2600 3500);
FORCEPROP 1 LASTPIN (-2650 3450) $PN 1
J 0
(-2640 3430);
DISPLAY 0.787234 (-2640 3430);
PAINT MONO (-2640 3430);
FORCEPROP 1 LASTPIN (-2650 3250) $PN 2
J 0
(-2640 3230);
DISPLAY 0.787234 (-2640 3230);
PAINT MONO (-2640 3230);
FORCEPROP 1 LAST MATERIAL X7R
J 0
(-2600 3250);
DISPLAY 0.489362 (-2600 3250);
PAINT SKYBLUE (-2600 3250);
FORCEPROP 1 LAST TOLERANCE 10%
J 0
(-2600 3300);
DISPLAY 0.489362 (-2600 3300);
PAINT SKYBLUE (-2600 3300);
FORCEPROP 1 LAST VOLTAGE 50V
J 0
(-2600 3350);
DISPLAY 0.489362 (-2600 3350);
PAINT SKYBLUE (-2600 3350);
FORCEPROP 1 LAST VALUE 0.001UF
J 0
(-2600 3400);
DISPLAY 0.489362 (-2600 3400);
PAINT SKYBLUE (-2600 3400);
FORCEPROP 1 LAST PACK_TYPE C0402
J 0
(-2600 3200);
DISPLAY 0.489362 (-2600 3200);
PAINT SKYBLUE (-2600 3200);
FORCEPROP 2 LAST ROOM USB3_HUB1_CYP
J 0
(-2625 3150);
DISPLAY 0.361702 (-2625 3150);
PAINT RED (-2625 3150);
FORCEPROP 2 LAST CDS_LIB pure_quanta
J 0
(-2650 3350);
DISPLAY INVISIBLE (-2650 3350);
FORCEPROP 1 LAST PATH I75
J 0
(-2600 3500);
DISPLAY 0.978723 (-2600 3500);
PAINT WHITE (-2600 3500);
DISPLAY INVISIBLE (-2600 3500);
FORCEPROP 1 LAST PART_NUMBER CH30106KB19
J 0
(-2600 3250);
DISPLAY 0.808511 (-2600 3250);
PAINT SKYBLUE (-2600 3250);
DISPLAY INVISIBLE (-2600 3250);
FORCEADD Q_CAP..1
(-3000 3350);
FORCEPROP 1 LAST LOCATION C6070
J 0
(-2950 3450);
DISPLAY 0.978723 (-2950 3450);
FORCEPROP 0 LAST $SEC 1
J 0
(-2950 3500);
DISPLAY 0.680851 (-2950 3500);
PAINT MONO (-2950 3500);
DISPLAY INVISIBLE (-2950 3500);
FORCEPROP 0 LAST CDS_SEC 1
J 0
(-2950 3500);
DISPLAY 0.680851 (-2950 3500);
DISPLAY INVISIBLE (-2950 3500);
FORCEPROP 1 LASTPIN (-3000 3450) $PN 1
J 0
(-2990 3430);
DISPLAY 0.787234 (-2990 3430);
PAINT MONO (-2990 3430);
FORCEPROP 1 LASTPIN (-3000 3250) $PN 2
J 0
(-2990 3230);
DISPLAY 0.787234 (-2990 3230);
PAINT MONO (-2990 3230);
FORCEPROP 1 LAST MATERIAL X7R
J 0
(-2950 3250);
DISPLAY 0.510638 (-2950 3250);
FORCEPROP 1 LAST PACK_TYPE C0402
J 0
(-2950 3150);
DISPLAY 0.510638 (-2950 3150);
FORCEPROP 1 LAST TOLERANCE 10%
J 0
(-2950 3300);
DISPLAY 0.510638 (-2950 3300);
FORCEPROP 1 LAST VOLTAGE 50V
J 0
(-2950 3350);
DISPLAY 0.510638 (-2950 3350);
FORCEPROP 1 LAST VALUE 0.01UF
J 0
(-2950 3400);
DISPLAY 0.510638 (-2950 3400);
FORCEPROP 2 LAST ROOM USB3_HUB1_CYP
J 0
(-2950 3200);
DISPLAY 0.361702 (-2950 3200);
PAINT RED (-2950 3200);
FORCEPROP 2 LAST CDS_LIB pure_quanta
J 0
(-3000 3350);
DISPLAY INVISIBLE (-3000 3350);
FORCEPROP 1 LAST PATH I76
J 0
(-2950 3500);
DISPLAY 0.978723 (-2950 3500);
PAINT WHITE (-2950 3500);
DISPLAY INVISIBLE (-2950 3500);
FORCEPROP 1 LAST PART_NUMBER CH31006KB18
J 0
(-2950 3200);
DISPLAY 0.638298 (-2950 3200);
DISPLAY INVISIBLE (-2950 3200);
FORCEADD GND..1
(-2600 3025);
FORCEPROP 3 LASTPIN (-2600 3075) SIG_NAME GND\g
J 0
(-2590 3085);
DISPLAY 0.659574 (-2590 3085);
PAINT MONO (-2590 3085);
DISPLAY INVISIBLE (-2590 3085);
FORCEPROP 2 LAST CDS_LIB pure_quanta_power
J 0
(-2600 3025);
DISPLAY INVISIBLE (-2600 3025);
FORCEPROP 1 LAST SIZE 1B
J 0
(-2525 2975);
DISPLAY 0.872340 (-2525 2975);
PAINT GREEN (-2525 2975);
DISPLAY INVISIBLE (-2525 2975);
FORCEPROP 1 LAST HDL_POWER GND
J 0
(-2600 3175);
DISPLAY 0.872340 (-2600 3175);
PAINT GREEN (-2600 3175);
DISPLAY INVISIBLE (-2600 3175);
FORCEPROP 1 LAST PATH I77
J 0
(-2525 3025);
DISPLAY 0.872340 (-2525 3025);
PAINT AQUA (-2525 3025);
DISPLAY INVISIBLE (-2525 3025);
FORCEADD Q_CAP..1
(-3500 3350);
FORCEPROP 1 LAST LOCATION C6068
J 0
(-3450 3450);
DISPLAY 0.978723 (-3450 3450);
FORCEPROP 0 LAST $SEC 1
J 0
(-3450 3500);
DISPLAY 0.680851 (-3450 3500);
PAINT MONO (-3450 3500);
DISPLAY INVISIBLE (-3450 3500);
FORCEPROP 0 LAST CDS_SEC 1
J 0
(-3450 3500);
DISPLAY 0.680851 (-3450 3500);
DISPLAY INVISIBLE (-3450 3500);
FORCEPROP 1 LASTPIN (-3500 3450) $PN 1
J 0
(-3490 3430);
DISPLAY 0.787234 (-3490 3430);
PAINT MONO (-3490 3430);
FORCEPROP 1 LASTPIN (-3500 3250) $PN 2
J 0
(-3490 3230);
DISPLAY 0.787234 (-3490 3230);
PAINT MONO (-3490 3230);
FORCEPROP 1 LAST PACK_TYPE C0402
J 0
(-3450 3150);
DISPLAY 0.510638 (-3450 3150);
FORCEPROP 1 LAST MATERIAL X7R
J 0
(-3450 3250);
DISPLAY 0.510638 (-3450 3250);
FORCEPROP 1 LAST TOLERANCE 10%
J 0
(-3450 3300);
DISPLAY 0.510638 (-3450 3300);
FORCEPROP 1 LAST VOLTAGE 50V
J 0
(-3450 3350);
DISPLAY 0.510638 (-3450 3350);
FORCEPROP 1 LAST VALUE 0.01UF
J 0
(-3450 3400);
DISPLAY 0.510638 (-3450 3400);
FORCEPROP 2 LAST ROOM USB3_HUB1_CYP
J 0
(-3450 3200);
DISPLAY 0.297872 (-3450 3200);
PAINT RED (-3450 3200);
FORCEPROP 2 LAST CDS_LIB pure_quanta
J 0
(-3500 3350);
DISPLAY INVISIBLE (-3500 3350);
FORCEPROP 1 LAST PATH I78
J 0
(-3450 3500);
DISPLAY 0.978723 (-3450 3500);
PAINT WHITE (-3450 3500);
DISPLAY INVISIBLE (-3450 3500);
FORCEPROP 1 LAST PART_NUMBER CH31006KB18
J 0
(-3450 3200);
DISPLAY 0.638298 (-3450 3200);
DISPLAY INVISIBLE (-3450 3200);
FORCEADD Q_CAP..1
(-3750 3350);
FORCEPROP 1 LAST LOCATION C6067
J 0
(-3700 3450);
DISPLAY 0.617021 (-3700 3450);
PAINT SKYBLUE (-3700 3450);
FORCEPROP 0 LAST $SEC 1
J 0
(-3700 3500);
DISPLAY 0.680851 (-3700 3500);
PAINT MONO (-3700 3500);
DISPLAY INVISIBLE (-3700 3500);
FORCEPROP 0 LAST CDS_SEC 1
J 0
(-3700 3500);
DISPLAY 0.680851 (-3700 3500);
DISPLAY INVISIBLE (-3700 3500);
FORCEPROP 1 LASTPIN (-3750 3450) $PN 1
J 0
(-3740 3430);
DISPLAY 0.787234 (-3740 3430);
PAINT MONO (-3740 3430);
FORCEPROP 1 LASTPIN (-3750 3250) $PN 2
J 0
(-3740 3230);
DISPLAY 0.787234 (-3740 3230);
PAINT MONO (-3740 3230);
FORCEPROP 1 LAST MATERIAL X7R
J 0
(-3700 3250);
DISPLAY 0.489362 (-3700 3250);
PAINT SKYBLUE (-3700 3250);
FORCEPROP 1 LAST VOLTAGE 50V
J 0
(-3700 3350);
DISPLAY 0.489362 (-3700 3350);
PAINT SKYBLUE (-3700 3350);
FORCEPROP 1 LAST TOLERANCE 10%
J 0
(-3700 3300);
DISPLAY 0.489362 (-3700 3300);
PAINT SKYBLUE (-3700 3300);
FORCEPROP 1 LAST VALUE 0.001UF
J 0
(-3700 3400);
DISPLAY 0.489362 (-3700 3400);
PAINT SKYBLUE (-3700 3400);
FORCEPROP 1 LAST PACK_TYPE C0402
J 0
(-3700 3200);
DISPLAY 0.489362 (-3700 3200);
PAINT SKYBLUE (-3700 3200);
FORCEPROP 2 LAST ROOM USB3_HUB1_CYP
J 0
(-3725 3150);
DISPLAY 0.361702 (-3725 3150);
PAINT RED (-3725 3150);
FORCEPROP 2 LAST CDS_LIB pure_quanta
J 0
(-3750 3350);
DISPLAY INVISIBLE (-3750 3350);
FORCEPROP 1 LAST PATH I79
J 0
(-3700 3500);
DISPLAY 0.978723 (-3700 3500);
PAINT WHITE (-3700 3500);
DISPLAY INVISIBLE (-3700 3500);
FORCEPROP 1 LAST PART_NUMBER CH30106KB19
J 0
(-3700 3250);
DISPLAY 0.808511 (-3700 3250);
PAINT SKYBLUE (-3700 3250);
DISPLAY INVISIBLE (-3700 3250);
FORCEADD GND..1
(-6550 3525);
FORCEPROP 3 LASTPIN (-6550 3575) SIG_NAME GND\g
J 0
(-6540 3585);
DISPLAY 0.659574 (-6540 3585);
PAINT MONO (-6540 3585);
DISPLAY INVISIBLE (-6540 3585);
FORCEPROP 2 LAST CDS_LIB pure_quanta_power
J 0
(-6550 3525);
DISPLAY INVISIBLE (-6550 3525);
FORCEPROP 1 LAST SIZE 1B
J 0
(-6475 3475);
DISPLAY 0.872340 (-6475 3475);
PAINT GREEN (-6475 3475);
DISPLAY INVISIBLE (-6475 3475);
FORCEPROP 1 LAST HDL_POWER GND
J 0
(-6550 3675);
DISPLAY 0.872340 (-6550 3675);
PAINT GREEN (-6550 3675);
DISPLAY INVISIBLE (-6550 3675);
FORCEPROP 1 LAST PATH I8
J 0
(-6475 3525);
DISPLAY 0.872340 (-6475 3525);
PAINT AQUA (-6475 3525);
DISPLAY INVISIBLE (-6475 3525);
FORCEADD GND..1
(-3700 3025);
FORCEPROP 3 LASTPIN (-3700 3075) SIG_NAME GND\g
J 0
(-3690 3085);
DISPLAY 0.659574 (-3690 3085);
PAINT MONO (-3690 3085);
DISPLAY INVISIBLE (-3690 3085);
FORCEPROP 1 LAST SIZE 1B
J 0
(-3625 2975);
DISPLAY 0.872340 (-3625 2975);
PAINT GREEN (-3625 2975);
DISPLAY INVISIBLE (-3625 2975);
FORCEPROP 2 LAST CDS_LIB pure_quanta_power
J 0
(-3700 3025);
DISPLAY INVISIBLE (-3700 3025);
FORCEPROP 1 LAST HDL_POWER GND
J 0
(-3700 3175);
DISPLAY 0.872340 (-3700 3175);
PAINT GREEN (-3700 3175);
DISPLAY INVISIBLE (-3700 3175);
FORCEPROP 1 LAST PATH I80
J 0
(-3625 3025);
DISPLAY 0.872340 (-3625 3025);
PAINT AQUA (-3625 3025);
DISPLAY INVISIBLE (-3625 3025);
FORCEADD Q_CAP..1
R 2
(-3700 2225);
FORCEPROP 1 LAST LOCATION C6080
J 2
(-3750 2325);
DISPLAY 0.978723 (-3750 2325);
FORCEPROP 0 LAST $SEC 1
J 0
(-3750 2375);
DISPLAY 0.680851 (-3750 2375);
PAINT MONO (-3750 2375);
DISPLAY INVISIBLE (-3750 2375);
FORCEPROP 0 LAST CDS_SEC 1
J 0
(-3750 2375);
DISPLAY 0.680851 (-3750 2375);
DISPLAY INVISIBLE (-3750 2375);
FORCEPROP 1 LASTPIN (-3700 2325) $PN 1
J 2
(-3710 2305);
DISPLAY 0.787234 (-3710 2305);
PAINT MONO (-3710 2305);
FORCEPROP 1 LASTPIN (-3700 2125) $PN 2
J 2
(-3710 2105);
DISPLAY 0.787234 (-3710 2105);
PAINT MONO (-3710 2105);
FORCEPROP 2 LAST ROOM USB3_HUB1_CYP
J 0
(-4025 2075);
DISPLAY 0.446809 (-4025 2075);
PAINT RED (-4025 2075);
FORCEPROP 1 LAST PACK_TYPE C0402
J 2
(-3750 2025);
DISPLAY 0.510638 (-3750 2025);
FORCEPROP 1 LAST VALUE 0.01UF
J 2
(-3750 2275);
DISPLAY 0.510638 (-3750 2275);
FORCEPROP 1 LAST VOLTAGE 50V
J 2
(-3750 2225);
DISPLAY 0.510638 (-3750 2225);
FORCEPROP 1 LAST MATERIAL X7R
J 2
(-3750 2125);
DISPLAY 0.510638 (-3750 2125);
FORCEPROP 1 LAST TOLERANCE 10%
J 2
(-3750 2175);
DISPLAY 0.510638 (-3750 2175);
FORCEPROP 2 LAST CDS_LIB pure_quanta
J 2
(-3700 2225);
DISPLAY INVISIBLE (-3700 2225);
FORCEPROP 1 LAST PATH I81
J 2
(-3750 2375);
DISPLAY 0.978723 (-3750 2375);
PAINT WHITE (-3750 2375);
DISPLAY INVISIBLE (-3750 2375);
FORCEPROP 1 LAST PART_NUMBER CH31006KB18
J 2
(-3750 2075);
DISPLAY 0.638298 (-3750 2075);
DISPLAY INVISIBLE (-3750 2075);
FORCEADD Q_CAP..1
R 2
(-3275 2225);
FORCEPROP 1 LAST LOCATION C6081
J 2
(-3325 2325);
DISPLAY 0.978723 (-3325 2325);
FORCEPROP 0 LAST $SEC 1
J 0
(-3325 2375);
DISPLAY 0.680851 (-3325 2375);
PAINT MONO (-3325 2375);
DISPLAY INVISIBLE (-3325 2375);
FORCEPROP 0 LAST CDS_SEC 1
J 0
(-3325 2375);
DISPLAY 0.680851 (-3325 2375);
DISPLAY INVISIBLE (-3325 2375);
FORCEPROP 1 LASTPIN (-3275 2325) $PN 1
J 2
(-3285 2305);
DISPLAY 0.787234 (-3285 2305);
PAINT MONO (-3285 2305);
FORCEPROP 1 LASTPIN (-3275 2125) $PN 2
J 2
(-3285 2105);
DISPLAY 0.787234 (-3285 2105);
PAINT MONO (-3285 2105);
FORCEPROP 1 LAST PACK_TYPE 0402
J 2
(-3325 2025);
DISPLAY 0.978723 (-3325 2025);
FORCEPROP 1 LAST MATERIAL X7R
J 2
(-3325 2125);
DISPLAY 0.978723 (-3325 2125);
FORCEPROP 1 LAST TOLERANCE 10%
J 2
(-3325 2175);
DISPLAY 0.978723 (-3325 2175);
FORCEPROP 1 LAST VOLTAGE 25V
J 2
(-3325 2225);
DISPLAY 0.978723 (-3325 2225);
FORCEPROP 1 LAST VALUE 0.1UF
J 2
(-3325 2275);
DISPLAY 0.978723 (-3325 2275);
FORCEPROP 2 LAST ROOM USB3_HUB1_CYP
J 0
(-3600 2075);
DISPLAY 0.446809 (-3600 2075);
PAINT RED (-3600 2075);
FORCEPROP 2 LAST CDS_LIB pure_quanta
J 0
(-3275 2225);
DISPLAY INVISIBLE (-3275 2225);
FORCEPROP 1 LAST PATH I82
J 2
(-3325 2375);
DISPLAY 0.978723 (-3325 2375);
PAINT WHITE (-3325 2375);
DISPLAY INVISIBLE (-3325 2375);
FORCEPROP 1 LAST PART_NUMBER CH4104K1B00
J 2
(-3325 2075);
DISPLAY 0.808511 (-3325 2075);
DISPLAY INVISIBLE (-3325 2075);
FORCEADD Q_CAP..1
(-3100 2225);
FORCEPROP 1 LAST LOCATION C6082
J 0
(-3050 2325);
DISPLAY 0.978723 (-3050 2325);
FORCEPROP 0 LAST $SEC 1
J 0
(-3050 2375);
DISPLAY 0.680851 (-3050 2375);
PAINT MONO (-3050 2375);
DISPLAY INVISIBLE (-3050 2375);
FORCEPROP 0 LAST CDS_SEC 1
J 0
(-3050 2375);
DISPLAY 0.680851 (-3050 2375);
DISPLAY INVISIBLE (-3050 2375);
FORCEPROP 1 LASTPIN (-3100 2325) $PN 1
J 0
(-3090 2305);
DISPLAY 0.787234 (-3090 2305);
PAINT MONO (-3090 2305);
FORCEPROP 1 LASTPIN (-3100 2125) $PN 2
J 0
(-3090 2105);
DISPLAY 0.787234 (-3090 2105);
PAINT MONO (-3090 2105);
FORCEPROP 1 LAST VALUE 1UF
J 0
(-3050 2275);
DISPLAY 0.978723 (-3050 2275);
FORCEPROP 1 LAST TOLERANCE 10%
J 0
(-3050 2175);
DISPLAY 0.978723 (-3050 2175);
FORCEPROP 1 LAST VOLTAGE 25V
J 0
(-3050 2225);
DISPLAY 0.978723 (-3050 2225);
FORCEPROP 1 LAST MATERIAL X6S
J 0
(-3050 2125);
DISPLAY 0.978723 (-3050 2125);
FORCEPROP 1 LAST PACK_TYPE C0402
J 0
(-3050 2025);
DISPLAY 0.978723 (-3050 2025);
FORCEPROP 2 LAST ROOM USB3_HUB1_CYP
J 0
(-3050 2375);
DISPLAY 0.680851 (-3050 2375);
PAINT RED (-3050 2375);
FORCEPROP 2 LAST CDS_LIB pure_quanta
J 0
(-3100 2225);
DISPLAY INVISIBLE (-3100 2225);
FORCEPROP 1 LAST PATH I83
J 0
(-3050 2375);
DISPLAY 0.978723 (-3050 2375);
PAINT WHITE (-3050 2375);
DISPLAY INVISIBLE (-3050 2375);
FORCEPROP 1 LAST PART_NUMBER CH5104KEB02
J 0
(-3050 2075);
DISPLAY 0.787234 (-3050 2075);
DISPLAY INVISIBLE (-3050 2075);
FORCEADD GND..1
(-3275 1775);
FORCEPROP 3 LASTPIN (-3275 1825) SIG_NAME GND\g
J 0
(-3265 1835);
DISPLAY 0.659574 (-3265 1835);
PAINT MONO (-3265 1835);
DISPLAY INVISIBLE (-3265 1835);
FORCEPROP 1 LAST SIZE 1B
J 0
(-3200 1725);
DISPLAY 0.872340 (-3200 1725);
PAINT GREEN (-3200 1725);
DISPLAY INVISIBLE (-3200 1725);
FORCEPROP 2 LAST CDS_LIB pure_quanta_power
J 0
(-3275 1775);
DISPLAY INVISIBLE (-3275 1775);
FORCEPROP 1 LAST HDL_POWER GND
J 0
(-3275 1925);
DISPLAY 0.872340 (-3275 1925);
PAINT GREEN (-3275 1925);
DISPLAY INVISIBLE (-3275 1925);
FORCEPROP 1 LAST PATH I84
J 0
(-3200 1775);
DISPLAY 0.872340 (-3200 1775);
PAINT AQUA (-3200 1775);
DISPLAY INVISIBLE (-3200 1775);
FORCEADD UNIVERSAL_POWER..1
(-8725 5875);
FORCEPROP 3 LASTPIN (-8725 5825) SIG_NAME P1V2_AUX\g
J 0
(-8715 5835);
DISPLAY 0.659574 (-8715 5835);
PAINT MONO (-8715 5835);
DISPLAY INVISIBLE (-8715 5835);
FORCEPROP 1 LAST HDL_POWER P1V2_AUX
J 1
(-8725 5925);
DISPLAY 0.489362 (-8725 5925);
PAINT GREEN (-8725 5925);
FORCEPROP 2 LAST BOM_COST VR_SYSTEM
J 0
(-8725 5975);
DISPLAY 0.617021 (-8725 5975);
PAINT PURPLE (-8725 5975);
DISPLAY INVISIBLE (-8725 5975);
FORCEPROP 2 LAST CDS_LIB pure_quanta_power
J 0
(-8725 5875);
DISPLAY INVISIBLE (-8725 5875);
FORCEPROP 1 LAST PATH I85
J 0
(-8675 5900);
DISPLAY 0.872340 (-8675 5900);
PAINT AQUA (-8675 5900);
DISPLAY INVISIBLE (-8675 5900);
FORCEADD UNIVERSAL_POWER..1
(-600 5725);
FORCEPROP 3 LASTPIN (-600 5675) SIG_NAME P1V2_AUX\g
J 0
(-590 5685);
DISPLAY 0.659574 (-590 5685);
PAINT MONO (-590 5685);
DISPLAY INVISIBLE (-590 5685);
FORCEPROP 1 LAST HDL_POWER P1V2_AUX
J 1
(-600 5775);
DISPLAY 0.489362 (-600 5775);
PAINT GREEN (-600 5775);
FORCEPROP 2 LAST BOM_COST VR_SYSTEM
J 0
(-600 5825);
DISPLAY 0.617021 (-600 5825);
PAINT PURPLE (-600 5825);
DISPLAY INVISIBLE (-600 5825);
FORCEPROP 2 LAST CDS_LIB pure_quanta_power
J 0
(-600 5725);
DISPLAY INVISIBLE (-600 5725);
FORCEPROP 1 LAST PATH I86
J 0
(-550 5750);
DISPLAY 0.872340 (-550 5750);
PAINT AQUA (-550 5750);
DISPLAY INVISIBLE (-550 5750);
FORCEADD UNIVERSAL_POWER..1
(-600 4200);
FORCEPROP 3 LASTPIN (-600 4150) SIG_NAME P1V2_AUX\g
J 0
(-590 4160);
DISPLAY 0.659574 (-590 4160);
PAINT MONO (-590 4160);
DISPLAY INVISIBLE (-590 4160);
FORCEPROP 1 LAST HDL_POWER P1V2_AUX
J 1
(-600 4250);
DISPLAY 0.489362 (-600 4250);
PAINT GREEN (-600 4250);
FORCEPROP 2 LAST BOM_COST VR_SYSTEM
J 0
(-600 4300);
DISPLAY 0.617021 (-600 4300);
PAINT PURPLE (-600 4300);
DISPLAY INVISIBLE (-600 4300);
FORCEPROP 2 LAST CDS_LIB pure_quanta_power
J 0
(-600 4200);
DISPLAY INVISIBLE (-600 4200);
FORCEPROP 1 LAST PATH I87
J 0
(-550 4225);
DISPLAY 0.872340 (-550 4225);
PAINT AQUA (-550 4225);
DISPLAY INVISIBLE (-550 4225);
FORCEADD UNIVERSAL_POWER..1
(-3275 2725);
FORCEPROP 3 LASTPIN (-3275 2675) SIG_NAME P1V2_AUX\g
J 0
(-3265 2685);
DISPLAY 0.659574 (-3265 2685);
PAINT MONO (-3265 2685);
DISPLAY INVISIBLE (-3265 2685);
FORCEPROP 1 LAST HDL_POWER P1V2_AUX
J 1
(-3275 2775);
DISPLAY 0.489362 (-3275 2775);
PAINT GREEN (-3275 2775);
FORCEPROP 2 LAST BOM_COST VR_SYSTEM
J 0
(-3275 2825);
DISPLAY 0.617021 (-3275 2825);
PAINT PURPLE (-3275 2825);
DISPLAY INVISIBLE (-3275 2825);
FORCEPROP 2 LAST CDS_LIB pure_quanta_power
J 0
(-3275 2725);
DISPLAY INVISIBLE (-3275 2725);
FORCEPROP 1 LAST PATH I88
J 0
(-3225 2750);
DISPLAY 0.872340 (-3225 2750);
PAINT AQUA (-3225 2750);
DISPLAY INVISIBLE (-3225 2750);
FORCEADD Q_CAP..1
(-7450 3200);
FORCEPROP 1 LAST LOCATION C6042
J 0
(-7400 3300);
DISPLAY 0.978723 (-7400 3300);
FORCEPROP 0 LAST $SEC 1
J 0
(-7400 3350);
DISPLAY 0.680851 (-7400 3350);
PAINT MONO (-7400 3350);
DISPLAY INVISIBLE (-7400 3350);
FORCEPROP 0 LAST CDS_SEC 1
J 0
(-7400 3350);
DISPLAY 0.680851 (-7400 3350);
DISPLAY INVISIBLE (-7400 3350);
FORCEPROP 1 LASTPIN (-7450 3300) $PN 1
J 0
(-7440 3280);
DISPLAY 0.787234 (-7440 3280);
PAINT MONO (-7440 3280);
FORCEPROP 1 LASTPIN (-7450 3100) $PN 2
J 0
(-7440 3080);
DISPLAY 0.787234 (-7440 3080);
PAINT MONO (-7440 3080);
FORCEPROP 1 LAST PACK_TYPE C0603
J 0
(-7400 3000);
DISPLAY 0.978723 (-7400 3000);
FORCEPROP 1 LAST MATERIAL X6S
J 0
(-7400 3100);
DISPLAY 0.978723 (-7400 3100);
FORCEPROP 1 LAST TOLERANCE 20%
J 0
(-7400 3150);
DISPLAY 0.978723 (-7400 3150);
FORCEPROP 1 LAST VOLTAGE 6.3V
J 0
(-7400 3200);
DISPLAY 0.978723 (-7400 3200);
FORCEPROP 1 LAST VALUE 22UF
J 0
(-7400 3250);
DISPLAY 0.978723 (-7400 3250);
FORCEPROP 2 LAST ROOM USB3_HUB1_CYP
J 0
(-7400 3350);
DISPLAY 0.553191 (-7400 3350);
PAINT RED (-7400 3350);
FORCEPROP 2 LAST CDS_LIB pure_quanta
J 0
(-7450 3200);
DISPLAY INVISIBLE (-7450 3200);
FORCEPROP 1 LAST PATH I9
J 0
(-7400 3350);
DISPLAY 0.978723 (-7400 3350);
PAINT WHITE (-7400 3350);
DISPLAY INVISIBLE (-7400 3350);
FORCEPROP 1 LAST PART_NUMBER CH6221ME900
J 0
(-7400 3050);
DISPLAY 0.787234 (-7400 3050);
DISPLAY INVISIBLE (-7400 3050);
FORCEADD QUANTA_TITLE_BLOCK_C..1
(0 0);
FORCEPROP 0 LAST CDS_CON_LAST_MODIFIED Thu Sep 14 16:12:46 2023
J 0
(-1885 15);
DISPLAY INVISIBLE (-1885 15);
FORCEPROP 1 LAST CUSTOM_TXT_CDS <CON_LAST_MODIFIED>
J 0
(-1885 15);
DISPLAY 0.978723 (-1885 15);
FORCEPROP 2 LAST CUSTOM_TXT_CDS <XR_PAGE_TITLE>
J 0
(-7890 5250);
DISPLAY 0.638298 (-7890 5250);
PAINT PINK (-7890 5250);
DISPLAY INVISIBLE (-7890 5250);
FORCEPROP 1 LAST CUSTOM_TXT_CDS <NAME_2>
J 0
(-3175 50);
FORCEPROP 1 LAST CUSTOM_TXT_CDS <NAME_1>
J 0
(-3175 175);
FORCEPROP 1 LAST CUSTOM_TXT_CDS <Q_NUMBER>
J 0
(-1403 103);
DISPLAY 1.212766 (-1403 103);
FORCEPROP 1 LAST CUSTOM_TXT_CDS <Q_PROJ>
J 0
(-2382 102);
DISPLAY 1.212766 (-2382 102);
FORCEPROP 1 LAST CUSTOM_TXT_CDS <Q_REV>
J 0
(-184 103);
DISPLAY 1.212766 (-184 103);
FORCEPROP 1 LAST CUSTOM_TXT_CDS <CON_PAGE_NUM> OF <CON_TOTAL_PAGES>
J 0
(-446 18);
DISPLAY 0.978723 (-446 18);
FORCEPROP 1 LAST Q_TITLE USB3.0 EXT HUB MAIN(2/2)
J 0
(-9275 75);
DISPLAY 2.446809 (-9275 75);
PAINT GREEN (-9275 75);
FORCEPROP 1 LAST CDS_LMAN_SYM_OUTLINE -9475,6775,100,-125
J 0
(0 0);
DISPLAY 0.468085 (0 0);
PAINT GREEN (0 0);
DISPLAY INVISIBLE (0 0);
FORCEPROP 2 LAST CDS_LIB pure_quanta
J 0
(0 0);
DISPLAY INVISIBLE (0 0);
FORCEPROP 2 LAST PAGE_BORDER TRUE
J 0
(-7890 5250);
DISPLAY 0.638298 (-7890 5250);
PAINT PINK (-7890 5250);
DISPLAY INVISIBLE (-7890 5250);
FORCEPROP 2 LAST CDS_XR_PAGE_TITLE CR-177 : @T6G_MB_LIB.T6G(SCH_1):PAGE177
J 0
(-7890 5250);
DISPLAY 0.638298 (-7890 5250);
PAINT PINK (-7890 5250);
DISPLAY INVISIBLE (-7890 5250);
FORCEPROP 1 LAST Q_DEPT BU9
J 1
(-3763 49);
DISPLAY 1.957447 (-3763 49);
PAINT GREEN (-3763 49);
DISPLAY INVISIBLE (-3763 49);
FORCEPROP 1 LAST COMMENT_BODY TRUE
J 0
(12 -13);
DISPLAY 0.978723 (12 -13);
PAINT GREEN (12 -13);
DISPLAY INVISIBLE (12 -13);
WIRE 16 -1 (-8500 5450)(-8725 5450);
WIRE 16 -1 (-8725 5450)(-8725 5825);
WIRE 16 -1 (-3100 2500)(-3100 2325);
WIRE 16 -1 (-3275 2500)(-3100 2500);
WIRE 16 -1 (-3275 2675)(-3275 2500);
WIRE 16 -1 (-3275 2325)(-3275 2500);
WIRE 16 -1 (-3700 2500)(-3275 2500);
WIRE 16 -1 (-3700 2325)(-3700 2500);
WIRE 16 -1 (-3975 2500)(-3700 2500);
WIRE 16 -1 (-3700 2125)(-3700 1925);
WIRE 16 -1 (-3700 1925)(-3275 1925);
WIRE 16 -1 (-3275 1925)(-3100 1925);
WIRE 16 -1 (-3275 2125)(-3275 1925);
WIRE 16 -1 (-3275 1925)(-3275 1825);
WIRE 16 -1 (-3100 1925)(-3100 2125);
WIRE 16 -1 (-1425 3450)(-1425 3500);
WIRE 16 -1 (-1425 3500)(-1175 3500);
WIRE 16 -1 (-1175 3550)(-1175 3500);
WIRE 16 -1 (-1175 3500)(-1175 3450);
WIRE 16 -1 (-1175 3650)(-1175 3550);
WIRE 16 -1 (-1175 3550)(-3975 3550);
WIRE 16 -1 (-1175 3750)(-1175 3650);
WIRE 16 -1 (-1175 3650)(-2025 3650);
WIRE 16 -1 (-2025 3650)(-2025 3500);
WIRE 16 -1 (-2025 3650)(-3975 3650);
WIRE 16 -1 (-1175 3850)(-1175 3750);
WIRE 16 -1 (-2650 3750)(-1175 3750);
WIRE 16 -1 (-2650 3500)(-2650 3750);
WIRE 16 -1 (-3975 3750)(-2650 3750);
WIRE 16 -1 (-1175 3950)(-1175 3850);
WIRE 16 -1 (-1175 3850)(-3250 3850);
WIRE 16 -1 (-2025 3500)(-1775 3500);
WIRE 16 -1 (-2025 3450)(-2025 3500);
WIRE 16 -1 (-1775 3500)(-1775 3450);
WIRE 16 -1 (-3250 3525)(-3250 3850);
WIRE 16 -1 (-3250 3850)(-3975 3850);
WIRE 16 -1 (-1175 3950)(-725 3950);
WIRE 16 -1 (-3750 3950)(-1175 3950);
WIRE 16 -1 (-2650 3500)(-2400 3500);
WIRE 16 -1 (-2650 3450)(-2650 3500);
WIRE 16 -1 (-2400 3500)(-2400 3450);
WIRE 16 -1 (-3975 3950)(-3750 3950);
WIRE 16 -1 (-3750 3500)(-3750 3950);
WIRE 16 -1 (-725 3950)(-600 3950);
WIRE 16 -1 (-725 3950)(-725 3850);
WIRE 16 -1 (-3250 3525)(-3000 3525);
WIRE 16 -1 (-3250 3450)(-3250 3525);
WIRE 16 -1 (-3000 3525)(-3000 3450);
WIRE 16 -1 (-600 4150)(-600 3950);
WIRE 16 -1 (-600 3950)(-325 3950);
WIRE 16 -1 (-600 3850)(-600 3950);
WIRE 16 -1 (-3750 3500)(-3500 3500);
WIRE 16 -1 (-3750 3450)(-3750 3500);
WIRE 16 -1 (-3500 3500)(-3500 3450);
WIRE 16 -1 (-325 3950)(-325 3850);
WIRE 16 -1 (-1775 5000)(-1775 4950);
WIRE 16 -1 (-2025 5000)(-1775 5000);
WIRE 16 -1 (-2025 5150)(-2025 5000);
WIRE 16 -1 (-2025 4950)(-2025 5000);
WIRE 16 -1 (-1175 5150)(-2025 5150);
WIRE 16 -1 (-2025 5150)(-3975 5150);
WIRE 16 -1 (-1175 5250)(-1175 5150);
WIRE 16 -1 (-1175 5150)(-1175 5050);
WIRE 16 -1 (-1175 5050)(-1175 5000);
WIRE 16 -1 (-1175 5050)(-3975 5050);
WIRE 16 -1 (-1175 5350)(-1175 5250);
WIRE 16 -1 (-2650 5250)(-1175 5250);
WIRE 16 -1 (-2650 5000)(-2650 5250);
WIRE 16 -1 (-3975 5250)(-2650 5250);
WIRE 16 -1 (-1175 5450)(-1175 5350);
WIRE 16 -1 (-1175 5350)(-3250 5350);
WIRE 16 -1 (-1175 5000)(-1175 4950);
WIRE 16 -1 (-1425 5000)(-1175 5000);
WIRE 16 -1 (-1425 4950)(-1425 5000);
WIRE 16 -1 (-3250 5350)(-3975 5350);
WIRE 16 -1 (-3250 5025)(-3250 5350);
WIRE 16 -1 (-1175 5450)(-725 5450);
WIRE 16 -1 (-3750 5450)(-1175 5450);
WIRE 16 -1 (-2650 5000)(-2400 5000);
WIRE 16 -1 (-2650 4950)(-2650 5000);
WIRE 16 -1 (-2400 5000)(-2400 4950);
WIRE 16 -1 (-3975 5450)(-3750 5450);
WIRE 16 -1 (-3750 5000)(-3750 5450);
WIRE 16 -1 (-600 5450)(-725 5450);
WIRE 16 -1 (-725 5450)(-725 5350);
WIRE 16 -1 (-3250 5025)(-3000 5025);
WIRE 16 -1 (-3250 4950)(-3250 5025);
WIRE 16 -1 (-3000 5025)(-3000 4950);
WIRE 16 -1 (-600 5450)(-325 5450);
WIRE 16 -1 (-600 5675)(-600 5450);
WIRE 16 -1 (-600 5350)(-600 5450);
WIRE 16 -1 (-3750 5000)(-3500 5000);
WIRE 16 -1 (-3750 4950)(-3750 5000);
WIRE 16 -1 (-3500 5000)(-3500 4950);
WIRE 16 -1 (-325 5450)(-325 5350);
WIRE 16 -1 (-3500 3250)(-3500 3125);
WIRE 16 -1 (-3500 3125)(-3700 3125);
WIRE 16 -1 (-3750 3125)(-3700 3125);
WIRE 16 -1 (-3700 3125)(-3700 3075);
WIRE 16 -1 (-3750 3250)(-3750 3125);
WIRE 16 -1 (-6425 3650)(-6425 3800);
WIRE 16 -1 (-6550 3650)(-6425 3650);
WIRE 16 -1 (-6850 3650)(-6550 3650);
WIRE 16 -1 (-6550 3650)(-6550 3575);
WIRE 16 -1 (-6850 3800)(-6850 3650);
WIRE 16 -1 (-2650 3250)(-2650 3125);
WIRE 16 -1 (-2650 3125)(-2600 3125);
WIRE 16 -1 (-2400 3125)(-2600 3125);
WIRE 16 -1 (-2600 3125)(-2600 3075);
WIRE 16 -1 (-2400 3250)(-2400 3125);
WIRE 16 -1 (-1175 3250)(-1175 3125);
WIRE 16 -1 (-1175 3125)(-1375 3125);
WIRE 16 -1 (-1425 3125)(-1375 3125);
WIRE 16 -1 (-1375 3125)(-1375 3075);
WIRE 16 -1 (-1425 3250)(-1425 3125);
WIRE 16 -1 (-600 3650)(-600 3475);
WIRE 16 -1 (-600 3475)(-325 3475);
WIRE 16 -1 (-725 3475)(-600 3475);
WIRE 16 -1 (-725 3650)(-725 3475);
WIRE 16 -1 (-325 3475)(-325 3650);
WIRE 16 -1 (-325 3475)(-325 3375);
WIRE 16 -1 (-3000 3250)(-3000 3125);
WIRE 16 -1 (-3000 3125)(-3200 3125);
WIRE 16 -1 (-3250 3125)(-3200 3125);
WIRE 16 -1 (-3200 3125)(-3200 3075);
WIRE 16 -1 (-3250 3250)(-3250 3125);
WIRE 16 -1 (-600 5150)(-600 4975);
WIRE 16 -1 (-600 4975)(-325 4975);
WIRE 16 -1 (-725 4975)(-600 4975);
WIRE 16 -1 (-725 5150)(-725 4975);
WIRE 16 -1 (-325 4975)(-325 5150);
WIRE 16 -1 (-325 4975)(-325 4875);
WIRE 16 -1 (-1425 4750)(-1425 4625);
WIRE 16 -1 (-1425 4625)(-1375 4625);
WIRE 16 -1 (-1175 4625)(-1375 4625);
WIRE 16 -1 (-1375 4625)(-1375 4575);
WIRE 16 -1 (-1175 4750)(-1175 4625);
WIRE 16 -1 (-2025 4750)(-2025 4625);
WIRE 16 -1 (-2025 4625)(-1975 4625);
WIRE 16 -1 (-1775 4625)(-1975 4625);
WIRE 16 -1 (-1975 4625)(-1975 4575);
WIRE 16 -1 (-1775 4750)(-1775 4625);
WIRE 16 -1 (-2650 4750)(-2650 4625);
WIRE 16 -1 (-2650 4625)(-2600 4625);
WIRE 16 -1 (-2400 4625)(-2600 4625);
WIRE 16 -1 (-2600 4625)(-2600 4575);
WIRE 16 -1 (-2400 4750)(-2400 4625);
WIRE 16 -1 (-3250 4750)(-3250 4625);
WIRE 16 -1 (-3250 4625)(-3200 4625);
WIRE 16 -1 (-3000 4625)(-3200 4625);
WIRE 16 -1 (-3200 4625)(-3200 4575);
WIRE 16 -1 (-3000 4750)(-3000 4625);
WIRE 16 -1 (-3750 4750)(-3750 4625);
WIRE 16 -1 (-3750 4625)(-3700 4625);
WIRE 16 -1 (-3500 4625)(-3700 4625);
WIRE 16 -1 (-3700 4625)(-3700 4575);
WIRE 16 -1 (-3500 4750)(-3500 4625);
WIRE 16 -1 (-5650 4800)(-5650 4625);
WIRE 16 -1 (-5875 4625)(-5650 4625);
WIRE 16 -1 (-5875 4800)(-5875 4625);
WIRE 16 -1 (-5875 4575)(-5875 4625);
WIRE 16 -1 (-5950 3300)(-5950 3400);
WIRE 16 -1 (-5425 3400)(-5950 3400);
WIRE 16 -1 (-5950 3400)(-6450 3400);
WIRE 16 -1 (-6450 3400)(-6450 3325);
WIRE 16 -1 (-6450 3400)(-6975 3400);
WIRE 16 -1 (-6975 3300)(-6975 3400);
WIRE 16 -1 (-6975 3400)(-7450 3400);
WIRE 16 -1 (-7450 3400)(-7525 3400);
WIRE 16 -1 (-7450 3300)(-7450 3400);
WIRE 16 -1 (-7525 3825)(-7525 3400);
WIRE 16 -1 (-8000 3400)(-7525 3400);
WIRE 16 -1 (-6225 4825)(-6225 4650);
WIRE 16 -1 (-6450 4650)(-6225 4650);
WIRE 16 -1 (-6450 4825)(-6450 4650);
WIRE 16 -1 (-6450 4600)(-6450 4650);
WIRE 16 -1 (-7225 4825)(-7225 4675);
WIRE 16 -1 (-7225 4675)(-7475 4675);
WIRE 16 -1 (-7475 4825)(-7475 4675);
WIRE 16 -1 (-7475 4675)(-7475 4625);
WIRE 16 -1 (-6950 4825)(-6950 4625);
WIRE 16 -1 (-6950 4625)(-6775 4625);
WIRE 16 -1 (-6775 4625)(-6725 4625);
WIRE 16 -1 (-6775 4575)(-6775 4625);
WIRE 16 -1 (-6725 4800)(-6725 4625);
WIRE 16 -1 (-7225 5100)(-7225 5025);
WIRE 16 -1 (-7475 5100)(-7225 5100);
WIRE 16 -1 (-7475 5100)(-7475 5150);
WIRE 16 -1 (-7475 5025)(-7475 5100);
WIRE 16 -1 (-5425 5150)(-7475 5150);
WIRE 16 -1 (-7475 5250)(-7475 5150);
WIRE 16 -1 (-7475 5250)(-6950 5250);
WIRE 16 -1 (-7475 5350)(-7475 5250);
WIRE 16 -1 (-7475 5350)(-6450 5350);
WIRE 16 -1 (-7475 5450)(-7475 5350);
WIRE 16 -1 (-6725 5250)(-6950 5250);
WIRE 16 -1 (-6950 5025)(-6950 5250);
WIRE 16 -1 (-5425 5250)(-6725 5250);
WIRE 16 -1 (-6725 5000)(-6725 5250);
WIRE 16 -1 (-5875 5450)(-7475 5450);
WIRE 16 -1 (-7475 5450)(-7875 5450);
WIRE 16 -1 (-6450 5350)(-5425 5350);
WIRE 16 -1 (-6450 5100)(-6450 5350);
WIRE 16 -1 (-6450 5100)(-6225 5100);
WIRE 16 -1 (-6450 5025)(-6450 5100);
WIRE 16 -1 (-7875 5775)(-7875 5450);
WIRE 16 -1 (-7875 5450)(-7975 5450);
WIRE 16 -1 (-5425 5450)(-5875 5450);
WIRE 16 -1 (-5875 5075)(-5875 5450);
WIRE 16 -1 (-5875 5075)(-5650 5075);
WIRE 16 -1 (-5875 5000)(-5875 5075);
WIRE 16 -1 (-7975 5350)(-7975 5450);
WIRE 16 -1 (-8200 5450)(-7975 5450);
WIRE 16 -1 (-6225 5100)(-6225 5025);
WIRE 16 -1 (-8200 5450)(-8300 5450);
WIRE 16 -1 (-8200 5350)(-8200 5450);
WIRE 16 -1 (-5650 5075)(-5650 5000);
WIRE 16 -1 (-8200 5150)(-8200 5000);
WIRE 16 -1 (-8200 5000)(-7975 5000);
WIRE 16 -1 (-7975 5000)(-7975 5150);
WIRE 16 -1 (-7975 5000)(-7975 4925);
WIRE 16 -1 (-5725 1875)(-5725 2025);
WIRE 16 -1 (-6025 1875)(-5725 1875);
WIRE 16 -1 (-6025 2025)(-6025 1875);
WIRE 16 -1 (-6025 1875)(-6025 1825);
WIRE 16 -1 (-6400 2025)(-6400 1850);
WIRE 16 -1 (-6725 1850)(-6400 1850);
WIRE 16 -1 (-6725 2025)(-6725 1850);
WIRE 16 -1 (-6725 1800)(-6725 1850);
WIRE 16 -1 (-6400 2325)(-6400 2225);
WIRE 16 -1 (-6725 2325)(-6400 2325);
WIRE 16 -1 (-6725 2325)(-6725 2500);
WIRE 16 -1 (-6725 2225)(-6725 2325);
WIRE 16 -1 (-6725 2500)(-5425 2500);
WIRE 16 -1 (-7525 2500)(-6725 2500);
WIRE 16 -1 (-7525 2600)(-7525 2500);
WIRE 16 -1 (-7525 2500)(-7525 2400);
WIRE 16 -1 (-7525 2400)(-5425 2400);
WIRE 16 -1 (-7525 2400)(-7525 2350);
WIRE 16 -1 (-7525 2600)(-6025 2600);
WIRE 16 -1 (-8150 2600)(-7525 2600);
WIRE 16 -1 (-8150 2325)(-8150 2600);
WIRE 16 -1 (-8350 2600)(-8150 2600);
WIRE 16 -1 (-5425 2600)(-6025 2600);
WIRE 16 -1 (-6025 2600)(-6025 2325);
WIRE 16 -1 (-7175 2350)(-7525 2350);
WIRE 16 -1 (-7525 2350)(-7525 2225);
WIRE 16 -1 (-7175 2225)(-7175 2350);
WIRE 16 -1 (-6025 2325)(-5725 2325);
WIRE 16 -1 (-6025 2225)(-6025 2325);
WIRE 16 -1 (-8400 2600)(-8350 2600);
WIRE 16 -1 (-8350 2325)(-8350 2600);
WIRE 16 -1 (-8400 2600)(-8400 3400);
WIRE 16 -1 (-5725 2325)(-5725 2225);
WIRE 16 -1 (-8400 3400)(-8400 4100);
WIRE 16 -1 (-8200 3400)(-8400 3400);
WIRE 16 -1 (-6850 4100)(-8400 4100);
WIRE 16 -1 (-8400 4100)(-8400 4200);
WIRE 16 -1 (-6425 4100)(-6850 4100);
WIRE 16 -1 (-6850 4000)(-6850 4100);
WIRE 16 -1 (-5425 4100)(-6425 4100);
WIRE 16 -1 (-6425 4000)(-6425 4100);
WIRE 16 -1 (-7175 2025)(-7175 1875);
WIRE 16 -1 (-7175 1875)(-7525 1875);
WIRE 16 -1 (-7525 2025)(-7525 1875);
WIRE 16 -1 (-7525 1875)(-7525 1825);
WIRE 16 -1 (-8350 2125)(-8350 1875);
WIRE 16 -1 (-8350 1875)(-8200 1875);
WIRE 16 -1 (-8200 1875)(-8150 1875);
WIRE 16 -1 (-8200 1875)(-8200 1800);
WIRE 16 -1 (-8150 1875)(-8150 2125);
WIRE 16 -1 (-7450 3100)(-7450 2975);
WIRE 16 -1 (-7450 2975)(-6975 2975);
WIRE 16 -1 (-6450 2975)(-6975 2975);
WIRE 16 -1 (-6975 3100)(-6975 2975);
WIRE 16 -1 (-6975 2975)(-6975 2875);
WIRE 16 -1 (-5950 2975)(-6450 2975);
WIRE 16 -1 (-6450 3125)(-6450 2975);
WIRE 16 -1 (-5950 3100)(-5950 2975);
WIRE 16 -1 (-2025 3250)(-2025 3125);
WIRE 16 -1 (-2025 3125)(-1975 3125);
WIRE 16 -1 (-1775 3125)(-1975 3125);
WIRE 16 -1 (-1975 3125)(-1975 3075);
WIRE 16 -1 (-1775 3250)(-1775 3125);
DOT 1 (-3700 2500);
DOT 1 (-1175 3550);
DOT 1 (-725 3950);
DOT 1 (-1175 3500);
DOT 1 (-1175 3950);
DOT 1 (-1375 3125);
DOT 1 (-1175 3750);
DOT 1 (-2650 3500);
DOT 1 (-3200 3125);
DOT 1 (-600 4975);
DOT 1 (-725 5450);
DOT 1 (-1175 5050);
DOT 1 (-2025 5150);
DOT 1 (-2650 5000);
DOT 1 (-3250 5025);
DOT 1 (-7525 2400);
DOT 1 (-7525 2600);
DOT 1 (-8150 2600);
DOT 1 (-8350 2600);
DOT 1 (-6450 2975);
DOT 1 (-6450 3400);
DOT 1 (-6975 3400);
DOT 1 (-7450 3400);
DOT 1 (-6425 4100);
DOT 1 (-6850 4100);
DOT 1 (-6450 5100);
DOT 1 (-6950 5250);
DOT 1 (-6725 5250);
DOT 1 (-7975 5450);
DOT 1 (-7475 5250);
DOT 1 (-8200 5450);
DOT 1 (-5875 5450);
DOT 1 (-3275 2500);
DOT 1 (-600 3950);
DOT 1 (-3275 1925);
DOT 1 (-325 3475);
DOT 1 (-3250 3525);
DOT 1 (-3250 3850);
DOT 1 (-1175 3850);
DOT 1 (-3750 3950);
DOT 1 (-2650 3750);
DOT 1 (-3200 4625);
DOT 1 (-600 5450);
DOT 1 (-325 4975);
DOT 1 (-1175 5450);
DOT 1 (-1175 5350);
DOT 1 (-1175 5250);
DOT 1 (-1175 5150);
DOT 1 (-1175 5000);
DOT 1 (-1375 4625);
DOT 1 (-2025 5000);
DOT 1 (-1975 4625);
DOT 1 (-2650 5250);
DOT 1 (-3250 5350);
DOT 1 (-3750 5450);
DOT 1 (-3750 5000);
DOT 1 (-3700 4625);
DOT 1 (-3700 3125);
DOT 1 (-3750 3500);
DOT 1 (-2600 3125);
DOT 1 (-2025 3500);
DOT 1 (-2025 3650);
DOT 1 (-1175 3650);
DOT 1 (-600 3475);
DOT 1 (-5875 4625);
DOT 1 (-5875 5075);
DOT 1 (-6450 5350);
DOT 1 (-7475 5150);
DOT 1 (-7475 5350);
DOT 1 (-7475 5100);
DOT 1 (-7475 5450);
DOT 1 (-6725 1850);
DOT 1 (-7525 1875);
DOT 1 (-7875 5450);
DOT 1 (-6025 1875);
DOT 1 (-6025 2600);
DOT 1 (-6975 2975);
DOT 1 (-6025 2325);
DOT 1 (-6725 2325);
DOT 1 (-6725 2500);
DOT 1 (-7525 2350);
DOT 1 (-6550 3650);
DOT 1 (-5950 3400);
DOT 1 (-7525 3400);
DOT 1 (-8400 3400);
DOT 1 (-7525 2500);
DOT 1 (-8400 4100);
DOT 1 (-8200 1875);
DOT 1 (-7975 5000);
DOT 1 (-7475 4675);
DOT 1 (-6775 4625);
DOT 1 (-6450 4650);
DOT 1 (-2600 4625);
DOT 1 (-1975 3125);
QUIT
